(lib_symbols
	(symbol "antmicroB2BConnectors:Plug_Samtec_ERM8_2x40_ERM8-040-05.0-L-DV-K-TR"
			(pin_names hide)
			(exclude_from_sim no)
			(in_bom yes)
			(on_board yes)
			(property "Reference" "J"
				(at 33.02 0 0)
				(effects
					(font
						(size 1.27 1.27)
						(thickness 0.15)
					)
					(justify left bottom)
				)
			)
			(property "Value" "Plug_Samtec_ERM8_2x40_ERM8-040-05.0-L-DV-K-TR"
				(at 33.02 -5.08 0)
				(effects
					(font
						(size 1.27 1.27)
						(thickness 0.15)
					)
					(justify left bottom)
					(hide yes)
				)
			)
			(property "Footprint" "antmicro-footprints:Conn_Plug_Samtec_ERM8_2x40_ERM8-040-05.0-L-DV-K-TR"
				(at 33.02 -7.62 0)
				(effects
					(font
						(size 1.27 1.27)
						(thickness 0.15)
					)
					(justify left bottom)
					(hide yes)
				)
			)
			(property "Datasheet" "https://suddendocs.samtec.com/catalog_english/erf8.pdf"
				(at 33.02 -10.16 0)
				(effects
					(font
						(size 1.27 1.27)
						(thickness 0.15)
					)
					(justify left bottom)
					(hide yes)
				)
			)
			(property "Description" "80 Position Connector Header, Center Strip Contacts Surface Mount Gold"
				(at 0 0 0)
				(effects
					(font
						(size 1.27 1.27)
					)
					(hide yes)
				)
			)
			(property "MPN" "ERM8-040-05.0-L-DV-K-TR"
				(at 33.02 -2.54 0)
				(effects
					(font
						(size 1.27 1.27)
						(thickness 0.15)
					)
					(justify left bottom)
				)
			)
			(property "Manufacturer" "Samtec"
				(at 33.02 -12.7 0)
				(effects
					(font
						(size 1.27 1.27)
						(thickness 0.15)
					)
					(justify left bottom)
					(hide yes)
				)
			)
			(property "Author" "Antmicro"
				(at 33.02 -17.78 0)
				(effects
					(font
						(size 1.27 1.27)
						(thickness 0.15)
					)
					(justify left bottom)
					(hide yes)
				)
			)
			(property "License" "Apache-2.0"
				(at 33.02 -20.32 0)
				(effects
					(font
						(size 1.27 1.27)
						(thickness 0.15)
					)
					(justify left bottom)
					(hide yes)
				)
			)
			(property "Pitch" "0.8 mm"
				(at 33.02 -15.24 0)
				(effects
					(font
						(size 1.27 1.27)
					)
					(justify left bottom)
					(hide yes)
				)
			)
			(property "ki_keywords" "CONNECTOR, B2B, PLUG"
				(at 0 0 0)
				(effects
					(font
						(size 1.27 1.27)
					)
					(hide yes)
				)
			)
			(symbol "Plug_Samtec_ERM8_2x40_ERM8-040-05.0-L-DV-K-TR_1_1"
				(rectangle
					(start 2.54 2.54)
					(end 8.89 -101.6)
					(stroke
						(width 0.254)
						(type default)
					)
					(fill
						(type background)
					)
				)
				(rectangle
					(start 3.81 1.27)
					(end 7.62 -100.33)
					(stroke
						(width 0.254)
						(type default)
					)
					(fill
						(type background)
					)
				)
				(pin passive line
					(at 0 0 0)
					(length 2.54)
					(name "~"
						(effects
							(font
								(size 1.27 1.27)
							)
						)
					)
					(number "1"
						(effects
							(font
								(size 1.27 1.27)
							)
						)
					)
				)
				(pin passive line
					(at 11.43 -10.16 180)
					(length 2.54)
					(name "~"
						(effects
							(font
								(size 1.27 1.27)
							)
						)
					)
					(number "10"
						(effects
							(font
								(size 1.27 1.27)
							)
						)
					)
				)
				(pin passive line
					(at 0 -12.7 0)
					(length 2.54)
					(name "~"
						(effects
							(font
								(size 1.27 1.27)
							)
						)
					)
					(number "11"
						(effects
							(font
								(size 1.27 1.27)
							)
						)
					)
				)
				(pin passive line
					(at 11.43 -12.7 180)
					(length 2.54)
					(name "~"
						(effects
							(font
								(size 1.27 1.27)
							)
						)
					)
					(number "12"
						(effects
							(font
								(size 1.27 1.27)
							)
						)
					)
				)
				(pin passive line
					(at 0 -15.24 0)
					(length 2.54)
					(name "~"
						(effects
							(font
								(size 1.27 1.27)
							)
						)
					)
					(number "13"
						(effects
							(font
								(size 1.27 1.27)
							)
						)
					)
				)
				(pin passive line
					(at 11.43 -15.24 180)
					(length 2.54)
					(name "~"
						(effects
							(font
								(size 1.27 1.27)
							)
						)
					)
					(number "14"
						(effects
							(font
								(size 1.27 1.27)
							)
						)
					)
				)
				(pin passive line
					(at 0 -17.78 0)
					(length 2.54)
					(name "~"
						(effects
							(font
								(size 1.27 1.27)
							)
						)
					)
					(number "15"
						(effects
							(font
								(size 1.27 1.27)
							)
						)
					)
				)
				(pin passive line
					(at 11.43 -17.78 180)
					(length 2.54)
					(name "~"
						(effects
							(font
								(size 1.27 1.27)
							)
						)
					)
					(number "16"
						(effects
							(font
								(size 1.27 1.27)
							)
						)
					)
				)
				(pin passive line
					(at 0 -20.32 0)
					(length 2.54)
					(name "~"
						(effects
							(font
								(size 1.27 1.27)
							)
						)
					)
					(number "17"
						(effects
							(font
								(size 1.27 1.27)
							)
						)
					)
				)
				(pin passive line
					(at 11.43 -20.32 180)
					(length 2.54)
					(name "~"
						(effects
							(font
								(size 1.27 1.27)
							)
						)
					)
					(number "18"
						(effects
							(font
								(size 1.27 1.27)
							)
						)
					)
				)
				(pin passive line
					(at 0 -22.86 0)
					(length 2.54)
					(name "~"
						(effects
							(font
								(size 1.27 1.27)
							)
						)
					)
					(number "19"
						(effects
							(font
								(size 1.27 1.27)
							)
						)
					)
				)
				(pin passive line
					(at 11.43 0 180)
					(length 2.54)
					(name "~"
						(effects
							(font
								(size 1.27 1.27)
							)
						)
					)
					(number "2"
						(effects
							(font
								(size 1.27 1.27)
							)
						)
					)
				)
				(pin passive line
					(at 11.43 -22.86 180)
					(length 2.54)
					(name "~"
						(effects
							(font
								(size 1.27 1.27)
							)
						)
					)
					(number "20"
						(effects
							(font
								(size 1.27 1.27)
							)
						)
					)
				)
				(pin passive line
					(at 0 -25.4 0)
					(length 2.54)
					(name "~"
						(effects
							(font
								(size 1.27 1.27)
							)
						)
					)
					(number "21"
						(effects
							(font
								(size 1.27 1.27)
							)
						)
					)
				)
				(pin passive line
					(at 11.43 -25.4 180)
					(length 2.54)
					(name "~"
						(effects
							(font
								(size 1.27 1.27)
							)
						)
					)
					(number "22"
						(effects
							(font
								(size 1.27 1.27)
							)
						)
					)
				)
				(pin passive line
					(at 0 -27.94 0)
					(length 2.54)
					(name "~"
						(effects
							(font
								(size 1.27 1.27)
							)
						)
					)
					(number "23"
						(effects
							(font
								(size 1.27 1.27)
							)
						)
					)
				)
				(pin passive line
					(at 11.43 -27.94 180)
					(length 2.54)
					(name "~"
						(effects
							(font
								(size 1.27 1.27)
							)
						)
					)
					(number "24"
						(effects
							(font
								(size 1.27 1.27)
							)
						)
					)
				)
				(pin passive line
					(at 0 -30.48 0)
					(length 2.54)
					(name "~"
						(effects
							(font
								(size 1.27 1.27)
							)
						)
					)
					(number "25"
						(effects
							(font
								(size 1.27 1.27)
							)
						)
					)
				)
				(pin passive line
					(at 11.43 -30.48 180)
					(length 2.54)
					(name "~"
						(effects
							(font
								(size 1.27 1.27)
							)
						)
					)
					(number "26"
						(effects
							(font
								(size 1.27 1.27)
							)
						)
					)
				)
				(pin passive line
					(at 0 -33.02 0)
					(length 2.54)
					(name "~"
						(effects
							(font
								(size 1.27 1.27)
							)
						)
					)
					(number "27"
						(effects
							(font
								(size 1.27 1.27)
							)
						)
					)
				)
				(pin passive line
					(at 11.43 -33.02 180)
					(length 2.54)
					(name "~"
						(effects
							(font
								(size 1.27 1.27)
							)
						)
					)
					(number "28"
						(effects
							(font
								(size 1.27 1.27)
							)
						)
					)
				)
				(pin passive line
					(at 0 -35.56 0)
					(length 2.54)
					(name "~"
						(effects
							(font
								(size 1.27 1.27)
							)
						)
					)
					(number "29"
						(effects
							(font
								(size 1.27 1.27)
							)
						)
					)
				)
				(pin passive line
					(at 0 -2.54 0)
					(length 2.54)
					(name "~"
						(effects
							(font
								(size 1.27 1.27)
							)
						)
					)
					(number "3"
						(effects
							(font
								(size 1.27 1.27)
							)
						)
					)
				)
				(pin passive line
					(at 11.43 -35.56 180)
					(length 2.54)
					(name "~"
						(effects
							(font
								(size 1.27 1.27)
							)
						)
					)
					(number "30"
						(effects
							(font
								(size 1.27 1.27)
							)
						)
					)
				)
				(pin passive line
					(at 0 -38.1 0)
					(length 2.54)
					(name "~"
						(effects
							(font
								(size 1.27 1.27)
							)
						)
					)
					(number "31"
						(effects
							(font
								(size 1.27 1.27)
							)
						)
					)
				)
				(pin passive line
					(at 11.43 -38.1 180)
					(length 2.54)
					(name "~"
						(effects
							(font
								(size 1.27 1.27)
							)
						)
					)
					(number "32"
						(effects
							(font
								(size 1.27 1.27)
							)
						)
					)
				)
				(pin passive line
					(at 0 -40.64 0)
					(length 2.54)
					(name "~"
						(effects
							(font
								(size 1.27 1.27)
							)
						)
					)
					(number "33"
						(effects
							(font
								(size 1.27 1.27)
							)
						)
					)
				)
				(pin passive line
					(at 11.43 -40.64 180)
					(length 2.54)
					(name "~"
						(effects
							(font
								(size 1.27 1.27)
							)
						)
					)
					(number "34"
						(effects
							(font
								(size 1.27 1.27)
							)
						)
					)
				)
				(pin passive line
					(at 0 -43.18 0)
					(length 2.54)
					(name "~"
						(effects
							(font
								(size 1.27 1.27)
							)
						)
					)
					(number "35"
						(effects
							(font
								(size 1.27 1.27)
							)
						)
					)
				)
				(pin passive line
					(at 11.43 -43.18 180)
					(length 2.54)
					(name "~"
						(effects
							(font
								(size 1.27 1.27)
							)
						)
					)
					(number "36"
						(effects
							(font
								(size 1.27 1.27)
							)
						)
					)
				)
				(pin passive line
					(at 0 -45.72 0)
					(length 2.54)
					(name "~"
						(effects
							(font
								(size 1.27 1.27)
							)
						)
					)
					(number "37"
						(effects
							(font
								(size 1.27 1.27)
							)
						)
					)
				)
				(pin passive line
					(at 11.43 -45.72 180)
					(length 2.54)
					(name "~"
						(effects
							(font
								(size 1.27 1.27)
							)
						)
					)
					(number "38"
						(effects
							(font
								(size 1.27 1.27)
							)
						)
					)
				)
				(pin passive line
					(at 0 -48.26 0)
					(length 2.54)
					(name "~"
						(effects
							(font
								(size 1.27 1.27)
							)
						)
					)
					(number "39"
						(effects
							(font
								(size 1.27 1.27)
							)
						)
					)
				)
				(pin passive line
					(at 11.43 -2.54 180)
					(length 2.54)
					(name "~"
						(effects
							(font
								(size 1.27 1.27)
							)
						)
					)
					(number "4"
						(effects
							(font
								(size 1.27 1.27)
							)
						)
					)
				)
				(pin passive line
					(at 11.43 -48.26 180)
					(length 2.54)
					(name "~"
						(effects
							(font
								(size 1.27 1.27)
							)
						)
					)
					(number "40"
						(effects
							(font
								(size 1.27 1.27)
							)
						)
					)
				)
				(pin passive line
					(at 0 -50.8 0)
					(length 2.54)
					(name "~"
						(effects
							(font
								(size 1.27 1.27)
							)
						)
					)
					(number "41"
						(effects
							(font
								(size 1.27 1.27)
							)
						)
					)
				)
				(pin passive line
					(at 11.43 -50.8 180)
					(length 2.54)
					(name "~"
						(effects
							(font
								(size 1.27 1.27)
							)
						)
					)
					(number "42"
						(effects
							(font
								(size 1.27 1.27)
							)
						)
					)
				)
				(pin passive line
					(at 0 -53.34 0)
					(length 2.54)
					(name "~"
						(effects
							(font
								(size 1.27 1.27)
							)
						)
					)
					(number "43"
						(effects
							(font
								(size 1.27 1.27)
							)
						)
					)
				)
				(pin passive line
					(at 11.43 -53.34 180)
					(length 2.54)
					(name "~"
						(effects
							(font
								(size 1.27 1.27)
							)
						)
					)
					(number "44"
						(effects
							(font
								(size 1.27 1.27)
							)
						)
					)
				)
				(pin passive line
					(at 0 -55.88 0)
					(length 2.54)
					(name "~"
						(effects
							(font
								(size 1.27 1.27)
							)
						)
					)
					(number "45"
						(effects
							(font
								(size 1.27 1.27)
							)
						)
					)
				)
				(pin passive line
					(at 11.43 -55.88 180)
					(length 2.54)
					(name "~"
						(effects
							(font
								(size 1.27 1.27)
							)
						)
					)
					(number "46"
						(effects
							(font
								(size 1.27 1.27)
							)
						)
					)
				)
				(pin passive line
					(at 0 -58.42 0)
					(length 2.54)
					(name "~"
						(effects
							(font
								(size 1.27 1.27)
							)
						)
					)
					(number "47"
						(effects
							(font
								(size 1.27 1.27)
							)
						)
					)
				)
				(pin passive line
					(at 11.43 -58.42 180)
					(length 2.54)
					(name "~"
						(effects
							(font
								(size 1.27 1.27)
							)
						)
					)
					(number "48"
						(effects
							(font
								(size 1.27 1.27)
							)
						)
					)
				)
				(pin passive line
					(at 0 -60.96 0)
					(length 2.54)
					(name "~"
						(effects
							(font
								(size 1.27 1.27)
							)
						)
					)
					(number "49"
						(effects
							(font
								(size 1.27 1.27)
							)
						)
					)
				)
				(pin passive line
					(at 0 -5.08 0)
					(length 2.54)
					(name "~"
						(effects
							(font
								(size 1.27 1.27)
							)
						)
					)
					(number "5"
						(effects
							(font
								(size 1.27 1.27)
							)
						)
					)
				)
				(pin passive line
					(at 11.43 -60.96 180)
					(length 2.54)
					(name "~"
						(effects
							(font
								(size 1.27 1.27)
							)
						)
					)
					(number "50"
						(effects
							(font
								(size 1.27 1.27)
							)
						)
					)
				)
				(pin passive line
					(at 0 -63.5 0)
					(length 2.54)
					(name "~"
						(effects
							(font
								(size 1.27 1.27)
							)
						)
					)
					(number "51"
						(effects
							(font
								(size 1.27 1.27)
							)
						)
					)
				)
				(pin passive line
					(at 11.43 -63.5 180)
					(length 2.54)
					(name "~"
						(effects
							(font
								(size 1.27 1.27)
							)
						)
					)
					(number "52"
						(effects
							(font
								(size 1.27 1.27)
							)
						)
					)
				)
				(pin passive line
					(at 0 -66.04 0)
					(length 2.54)
					(name "~"
						(effects
							(font
								(size 1.27 1.27)
							)
						)
					)
					(number "53"
						(effects
							(font
								(size 1.27 1.27)
							)
						)
					)
				)
				(pin passive line
					(at 11.43 -66.04 180)
					(length 2.54)
					(name "~"
						(effects
							(font
								(size 1.27 1.27)
							)
						)
					)
					(number "54"
						(effects
							(font
								(size 1.27 1.27)
							)
						)
					)
				)
				(pin passive line
					(at 0 -68.58 0)
					(length 2.54)
					(name "~"
						(effects
							(font
								(size 1.27 1.27)
							)
						)
					)
					(number "55"
						(effects
							(font
								(size 1.27 1.27)
							)
						)
					)
				)
				(pin passive line
					(at 11.43 -68.58 180)
					(length 2.54)
					(name "~"
						(effects
							(font
								(size 1.27 1.27)
							)
						)
					)
					(number "56"
						(effects
							(font
								(size 1.27 1.27)
							)
						)
					)
				)
				(pin passive line
					(at 0 -71.12 0)
					(length 2.54)
					(name "~"
						(effects
							(font
								(size 1.27 1.27)
							)
						)
					)
					(number "57"
						(effects
							(font
								(size 1.27 1.27)
							)
						)
					)
				)
				(pin passive line
					(at 11.43 -71.12 180)
					(length 2.54)
					(name "~"
						(effects
							(font
								(size 1.27 1.27)
							)
						)
					)
					(number "58"
						(effects
							(font
								(size 1.27 1.27)
							)
						)
					)
				)
				(pin passive line
					(at 0 -73.66 0)
					(length 2.54)
					(name "~"
						(effects
							(font
								(size 1.27 1.27)
							)
						)
					)
					(number "59"
						(effects
							(font
								(size 1.27 1.27)
							)
						)
					)
				)
				(pin passive line
					(at 11.43 -5.08 180)
					(length 2.54)
					(name "~"
						(effects
							(font
								(size 1.27 1.27)
							)
						)
					)
					(number "6"
						(effects
							(font
								(size 1.27 1.27)
							)
						)
					)
				)
				(pin passive line
					(at 11.43 -73.66 180)
					(length 2.54)
					(name "~"
						(effects
							(font
								(size 1.27 1.27)
							)
						)
					)
					(number "60"
						(effects
							(font
								(size 1.27 1.27)
							)
						)
					)
				)
				(pin passive line
					(at 0 -76.2 0)
					(length 2.54)
					(name "~"
						(effects
							(font
								(size 1.27 1.27)
							)
						)
					)
					(number "61"
						(effects
							(font
								(size 1.27 1.27)
							)
						)
					)
				)
				(pin passive line
					(at 11.43 -76.2 180)
					(length 2.54)
					(name "~"
						(effects
							(font
								(size 1.27 1.27)
							)
						)
					)
					(number "62"
						(effects
							(font
								(size 1.27 1.27)
							)
						)
					)
				)
				(pin passive line
					(at 0 -78.74 0)
					(length 2.54)
					(name "~"
						(effects
							(font
								(size 1.27 1.27)
							)
						)
					)
					(number "63"
						(effects
							(font
								(size 1.27 1.27)
							)
						)
					)
				)
				(pin passive line
					(at 11.43 -78.74 180)
					(length 2.54)
					(name "~"
						(effects
							(font
								(size 1.27 1.27)
							)
						)
					)
					(number "64"
						(effects
							(font
								(size 1.27 1.27)
							)
						)
					)
				)
				(pin passive line
					(at 0 -81.28 0)
					(length 2.54)
					(name "~"
						(effects
							(font
								(size 1.27 1.27)
							)
						)
					)
					(number "65"
						(effects
							(font
								(size 1.27 1.27)
							)
						)
					)
				)
				(pin passive line
					(at 11.43 -81.28 180)
					(length 2.54)
					(name "~"
						(effects
							(font
								(size 1.27 1.27)
							)
						)
					)
					(number "66"
						(effects
							(font
								(size 1.27 1.27)
							)
						)
					)
				)
				(pin passive line
					(at 0 -83.82 0)
					(length 2.54)
					(name "~"
						(effects
							(font
								(size 1.27 1.27)
							)
						)
					)
					(number "67"
						(effects
							(font
								(size 1.27 1.27)
							)
						)
					)
				)
				(pin passive line
					(at 11.43 -83.82 180)
					(length 2.54)
					(name "~"
						(effects
							(font
								(size 1.27 1.27)
							)
						)
					)
					(number "68"
						(effects
							(font
								(size 1.27 1.27)
							)
						)
					)
				)
				(pin passive line
					(at 0 -86.36 0)
					(length 2.54)
					(name "~"
						(effects
							(font
								(size 1.27 1.27)
							)
						)
					)
					(number "69"
						(effects
							(font
								(size 1.27 1.27)
							)
						)
					)
				)
				(pin passive line
					(at 0 -7.62 0)
					(length 2.54)
					(name "~"
						(effects
							(font
								(size 1.27 1.27)
							)
						)
					)
					(number "7"
						(effects
							(font
								(size 1.27 1.27)
							)
						)
					)
				)
				(pin passive line
					(at 11.43 -86.36 180)
					(length 2.54)
					(name "~"
						(effects
							(font
								(size 1.27 1.27)
							)
						)
					)
					(number "70"
						(effects
							(font
								(size 1.27 1.27)
							)
						)
					)
				)
				(pin passive line
					(at 0 -88.9 0)
					(length 2.54)
					(name "~"
						(effects
							(font
								(size 1.27 1.27)
							)
						)
					)
					(number "71"
						(effects
							(font
								(size 1.27 1.27)
							)
						)
					)
				)
				(pin passive line
					(at 11.43 -88.9 180)
					(length 2.54)
					(name "~"
						(effects
							(font
								(size 1.27 1.27)
							)
						)
					)
					(number "72"
						(effects
							(font
								(size 1.27 1.27)
							)
						)
					)
				)
				(pin passive line
					(at 0 -91.44 0)
					(length 2.54)
					(name "~"
						(effects
							(font
								(size 1.27 1.27)
							)
						)
					)
					(number "73"
						(effects
							(font
								(size 1.27 1.27)
							)
						)
					)
				)
				(pin passive line
					(at 11.43 -91.44 180)
					(length 2.54)
					(name "~"
						(effects
							(font
								(size 1.27 1.27)
							)
						)
					)
					(number "74"
						(effects
							(font
								(size 1.27 1.27)
							)
						)
					)
				)
				(pin passive line
					(at 0 -93.98 0)
					(length 2.54)
					(name "~"
						(effects
							(font
								(size 1.27 1.27)
							)
						)
					)
					(number "75"
						(effects
							(font
								(size 1.27 1.27)
							)
						)
					)
				)
				(pin passive line
					(at 11.43 -93.98 180)
					(length 2.54)
					(name "~"
						(effects
							(font
								(size 1.27 1.27)
							)
						)
					)
					(number "76"
						(effects
							(font
								(size 1.27 1.27)
							)
						)
					)
				)
				(pin passive line
					(at 0 -96.52 0)
					(length 2.54)
					(name "~"
						(effects
							(font
								(size 1.27 1.27)
							)
						)
					)
					(number "77"
						(effects
							(font
								(size 1.27 1.27)
							)
						)
					)
				)
				(pin passive line
					(at 11.43 -96.52 180)
					(length 2.54)
					(name "~"
						(effects
							(font
								(size 1.27 1.27)
							)
						)
					)
					(number "78"
						(effects
							(font
								(size 1.27 1.27)
							)
						)
					)
				)
				(pin passive line
					(at 0 -99.06 0)
					(length 2.54)
					(name "~"
						(effects
							(font
								(size 1.27 1.27)
							)
						)
					)
					(number "79"
						(effects
							(font
								(size 1.27 1.27)
							)
						)
					)
				)
				(pin passive line
					(at 11.43 -7.62 180)
					(length 2.54)
					(name "~"
						(effects
							(font
								(size 1.27 1.27)
							)
						)
					)
					(number "8"
						(effects
							(font
								(size 1.27 1.27)
							)
						)
					)
				)
				(pin passive line
					(at 11.43 -99.06 180)
					(length 2.54)
					(name "~"
						(effects
							(font
								(size 1.27 1.27)
							)
						)
					)
					(number "80"
						(effects
							(font
								(size 1.27 1.27)
							)
						)
					)
				)
				(pin passive line
					(at 0 -10.16 0)
					(length 2.54)
					(name "~"
						(effects
							(font
								(size 1.27 1.27)
							)
						)
					)
					(number "9"
						(effects
							(font
								(size 1.27 1.27)
							)
						)
					)
				)
			)
		)
	(symbol "antmicroCapacitors0402:C_100n_0402"
			(pin_numbers hide)
			(pin_names hide)
			(exclude_from_sim no)
			(in_bom yes)
			(on_board yes)
			(property "Reference" "C"
				(at 20.32 -5.08 0)
				(effects
					(font
						(size 1.27 1.27)
						(thickness 0.15)
					)
					(justify left bottom)
				)
			)
			(property "Value" "C_100n_0402"
				(at 20.32 -10.16 0)
				(effects
					(font
						(size 1.27 1.27)
						(thickness 0.15)
					)
					(justify left bottom)
					(hide yes)
				)
			)
			(property "Footprint" "antmicro-footprints:C_0402_1005Metric"
				(at 20.32 -12.7 0)
				(effects
					(font
						(size 1.27 1.27)
						(thickness 0.15)
					)
					(justify left bottom)
					(hide yes)
				)
			)
			(property "Datasheet" "https://www.murata.com/products/productdetail?partno=GRM155R61H104KE14%23"
				(at 20.32 -15.24 0)
				(effects
					(font
						(size 1.27 1.27)
						(thickness 0.15)
					)
					(justify left bottom)
					(hide yes)
				)
			)
			(property "Description" "SMD Multilayer Ceramic Capacitor, 0.1 µF, 50 V, 0402 [1005 Metric], ± 10%, X5R, GRM Series"
				(at 0 0 0)
				(effects
					(font
						(size 1.27 1.27)
					)
					(hide yes)
				)
			)
			(property "MPN" "GRM155R61H104KE14D"
				(at 20.32 -17.78 0)
				(effects
					(font
						(size 1.27 1.27)
						(thickness 0.15)
					)
					(justify left bottom)
					(hide yes)
				)
			)
			(property "Manufacturer" "Murata"
				(at 20.32 -20.32 0)
				(effects
					(font
						(size 1.27 1.27)
						(thickness 0.15)
					)
					(justify left bottom)
					(hide yes)
				)
			)
			(property "License" "Apache-2.0"
				(at 20.32 -22.86 0)
				(effects
					(font
						(size 1.27 1.27)
						(thickness 0.15)
					)
					(justify left bottom)
					(hide yes)
				)
			)
			(property "Author" "Antmicro"
				(at 20.32 -25.4 0)
				(effects
					(font
						(size 1.27 1.27)
						(thickness 0.15)
					)
					(justify left bottom)
					(hide yes)
				)
			)
			(property "Val" "100n"
				(at 20.32 -7.62 0)
				(effects
					(font
						(size 1.27 1.27)
						(thickness 0.15)
					)
					(justify left bottom)
				)
			)
			(property "Voltage" "50V"
				(at 20.32 -27.94 0)
				(effects
					(font
						(size 1.27 1.27)
					)
					(justify left bottom)
					(hide yes)
				)
			)
			(property "Dielectric" "X5R"
				(at 20.32 -30.48 0)
				(effects
					(font
						(size 1.27 1.27)
					)
					(justify left bottom)
					(hide yes)
				)
			)
			(property "ki_keywords" "0402, SMT, CAPACITOR, PASSIVE, CERAMIC, MLCC"
				(at 0 0 0)
				(effects
					(font
						(size 1.27 1.27)
					)
					(hide yes)
				)
			)
			(symbol "C_100n_0402_0_1"
				(polyline
					(pts
						(xy 2.032 -1.524) (xy 2.032 1.524)
					)
					(stroke
						(width 0.3048)
						(type default)
					)
					(fill
						(type none)
					)
				)
				(polyline
					(pts
						(xy 3.048 -1.524) (xy 3.048 1.524)
					)
					(stroke
						(width 0.3302)
						(type default)
					)
					(fill
						(type none)
					)
				)
			)
			(symbol "C_100n_0402_1_1"
				(pin passive line
					(at 0 0 0)
					(length 2.032)
					(name "~"
						(effects
							(font
								(size 1.27 1.27)
							)
						)
					)
					(number "1"
						(effects
							(font
								(size 1.27 1.27)
							)
						)
					)
				)
				(pin passive line
					(at 5.08 0 180)
					(length 2.032)
					(name "~"
						(effects
							(font
								(size 1.27 1.27)
							)
						)
					)
					(number "2"
						(effects
							(font
								(size 1.27 1.27)
							)
						)
					)
				)
			)
		)
	(symbol "antmicroCapacitors0402:C_10u_0402"
			(pin_numbers hide)
			(pin_names hide)
			(exclude_from_sim no)
			(in_bom yes)
			(on_board yes)
			(property "Reference" "C"
				(at 20.32 -5.08 0)
				(effects
					(font
						(size 1.27 1.27)
						(thickness 0.15)
					)
					(justify left bottom)
				)
			)
			(property "Value" "C_10u_0402"
				(at 20.32 -10.16 0)
				(effects
					(font
						(size 1.27 1.27)
						(thickness 0.15)
					)
					(justify left bottom)
					(hide yes)
				)
			)
			(property "Footprint" "antmicro-footprints:C_0402_1005Metric"
				(at 20.32 -12.7 0)
				(effects
					(font
						(size 1.27 1.27)
						(thickness 0.15)
					)
					(justify left bottom)
					(hide yes)
				)
			)
			(property "Datasheet" "https://www.yageo.com/en/Chart/Download/pdf/CC0402MRX5R5BB106"
				(at 20.32 -15.24 0)
				(effects
					(font
						(size 1.27 1.27)
						(thickness 0.15)
					)
					(justify left bottom)
					(hide yes)
				)
			)
			(property "Description" "SMD Multilayer Ceramic Capacitor, 10 µF, 6.3 V, 0402 [1005 Metric], ± 20%, X5R, CC Series"
				(at 0 0 0)
				(effects
					(font
						(size 1.27 1.27)
					)
					(hide yes)
				)
			)
			(property "MPN" "CC0402MRX5R5BB106"
				(at 20.32 -17.78 0)
				(effects
					(font
						(size 1.27 1.27)
						(thickness 0.15)
					)
					(justify left bottom)
					(hide yes)
				)
			)
			(property "Manufacturer" "YAGEO"
				(at 20.32 -20.32 0)
				(effects
					(font
						(size 1.27 1.27)
						(thickness 0.15)
					)
					(justify left bottom)
					(hide yes)
				)
			)
			(property "License" "Apache-2.0"
				(at 20.32 -22.86 0)
				(effects
					(font
						(size 1.27 1.27)
						(thickness 0.15)
					)
					(justify left bottom)
					(hide yes)
				)
			)
			(property "Author" "Antmicro"
				(at 20.32 -25.4 0)
				(effects
					(font
						(size 1.27 1.27)
						(thickness 0.15)
					)
					(justify left bottom)
					(hide yes)
				)
			)
			(property "Val" "10u"
				(at 20.32 -7.62 0)
				(effects
					(font
						(size 1.27 1.27)
						(thickness 0.15)
					)
					(justify left bottom)
				)
			)
			(property "Voltage" ""
				(at 20.32 -27.94 0)
				(effects
					(font
						(size 1.27 1.27)
					)
					(justify left bottom)
					(hide yes)
				)
			)
			(property "Dielectric" ""
				(at 20.32 -30.48 0)
				(effects
					(font
						(size 1.27 1.27)
					)
					(justify left bottom)
					(hide yes)
				)
			)
			(property "ki_keywords" "0402, SMT, CAPACITOR, PASSIVE, MLCC, CERAMIC"
				(at 0 0 0)
				(effects
					(font
						(size 1.27 1.27)
					)
					(hide yes)
				)
			)
			(symbol "C_10u_0402_0_1"
				(polyline
					(pts
						(xy 2.032 -1.524) (xy 2.032 1.524)
					)
					(stroke
						(width 0.3048)
						(type default)
					)
					(fill
						(type none)
					)
				)
				(polyline
					(pts
						(xy 3.048 -1.524) (xy 3.048 1.524)
					)
					(stroke
						(width 0.3302)
						(type default)
					)
					(fill
						(type none)
					)
				)
			)
			(symbol "C_10u_0402_1_1"
				(pin passive line
					(at 0 0 0)
					(length 2.032)
					(name "~"
						(effects
							(font
								(size 1.27 1.27)
							)
						)
					)
					(number "1"
						(effects
							(font
								(size 1.27 1.27)
							)
						)
					)
				)
				(pin passive line
					(at 5.08 0 180)
					(length 2.032)
					(name "~"
						(effects
							(font
								(size 1.27 1.27)
							)
						)
					)
					(number "2"
						(effects
							(font
								(size 1.27 1.27)
							)
						)
					)
				)
			)
		)
	(symbol "antmicroCapacitors0402:C_220n_0402"
			(pin_numbers hide)
			(pin_names hide)
			(exclude_from_sim no)
			(in_bom yes)
			(on_board yes)
			(property "Reference" "C"
				(at 20.32 -5.08 0)
				(effects
					(font
						(size 1.27 1.27)
						(thickness 0.15)
					)
					(justify left bottom)
				)
			)
			(property "Value" "C_220n_0402"
				(at 20.32 -10.16 0)
				(effects
					(font
						(size 1.27 1.27)
						(thickness 0.15)
					)
					(justify left bottom)
					(hide yes)
				)
			)
			(property "Footprint" "antmicro-footprints:C_0402_1005Metric"
				(at 20.32 -12.7 0)
				(effects
					(font
						(size 1.27 1.27)
						(thickness 0.15)
					)
					(justify left bottom)
					(hide yes)
				)
			)
			(property "Datasheet" "https://www.yageo.com/en/Chart/Download/pdf/CC0402KRX5R6BB224"
				(at 20.32 -15.24 0)
				(effects
					(font
						(size 1.27 1.27)
						(thickness 0.15)
					)
					(justify left bottom)
					(hide yes)
				)
			)
			(property "Description" "SMD Multilayer Ceramic Capacitor, 0.22 µF, 10 V, 0402 [1005 Metric], ± 10%, X5R, CC Series"
				(at 0 0 0)
				(effects
					(font
						(size 1.27 1.27)
					)
					(hide yes)
				)
			)
			(property "MPN" "CC0402KRX5R6BB224"
				(at 20.32 -17.78 0)
				(effects
					(font
						(size 1.27 1.27)
						(thickness 0.15)
					)
					(justify left bottom)
					(hide yes)
				)
			)
			(property "Manufacturer" "YAGEO"
				(at 20.32 -20.32 0)
				(effects
					(font
						(size 1.27 1.27)
						(thickness 0.15)
					)
					(justify left bottom)
					(hide yes)
				)
			)
			(property "License" "Apache-2.0"
				(at 20.32 -22.86 0)
				(effects
					(font
						(size 1.27 1.27)
						(thickness 0.15)
					)
					(justify left bottom)
					(hide yes)
				)
			)
			(property "Author" "Antmicro"
				(at 20.32 -25.4 0)
				(effects
					(font
						(size 1.27 1.27)
						(thickness 0.15)
					)
					(justify left bottom)
					(hide yes)
				)
			)
			(property "Val" "220n"
				(at 20.32 -7.62 0)
				(effects
					(font
						(size 1.27 1.27)
						(thickness 0.15)
					)
					(justify left bottom)
				)
			)
			(property "Voltage" ""
				(at 20.32 -27.94 0)
				(effects
					(font
						(size 1.27 1.27)
					)
					(justify left bottom)
					(hide yes)
				)
			)
			(property "Dielectric" ""
				(at 20.32 -30.48 0)
				(effects
					(font
						(size 1.27 1.27)
					)
					(justify left bottom)
					(hide yes)
				)
			)
			(property "ki_keywords" "0402, SMT, CAPACITOR, PASSIVE, MLCC, CERAMIC"
				(at 0 0 0)
				(effects
					(font
						(size 1.27 1.27)
					)
					(hide yes)
				)
			)
			(symbol "C_220n_0402_0_1"
				(polyline
					(pts
						(xy 2.032 -1.524) (xy 2.032 1.524)
					)
					(stroke
						(width 0.3048)
						(type default)
					)
					(fill
						(type none)
					)
				)
				(polyline
					(pts
						(xy 3.048 -1.524) (xy 3.048 1.524)
					)
					(stroke
						(width 0.3302)
						(type default)
					)
					(fill
						(type none)
					)
				)
			)
			(symbol "C_220n_0402_1_1"
				(pin passive line
					(at 0 0 0)
					(length 2.032)
					(name "~"
						(effects
							(font
								(size 1.27 1.27)
							)
						)
					)
					(number "1"
						(effects
							(font
								(size 1.27 1.27)
							)
						)
					)
				)
				(pin passive line
					(at 5.08 0 180)
					(length 2.032)
					(name "~"
						(effects
							(font
								(size 1.27 1.27)
							)
						)
					)
					(number "2"
						(effects
							(font
								(size 1.27 1.27)
							)
						)
					)
				)
			)
		)
	(symbol "antmicroCapacitorsmisc:C_100u_0805"
			(pin_numbers hide)
			(pin_names hide)
			(exclude_from_sim no)
			(in_bom yes)
			(on_board yes)
			(property "Reference" "C"
				(at 20.32 -5.08 0)
				(effects
					(font
						(size 1.27 1.27)
						(thickness 0.15)
					)
					(justify left bottom)
				)
			)
			(property "Value" "C_100u_0805"
				(at 20.32 -10.16 0)
				(effects
					(font
						(size 1.27 1.27)
						(thickness 0.15)
					)
					(justify left bottom)
					(hide yes)
				)
			)
			(property "Footprint" "antmicro-footprints:C_0805_2012Metric"
				(at 20.32 -12.7 0)
				(effects
					(font
						(size 1.27 1.27)
						(thickness 0.15)
					)
					(justify left bottom)
					(hide yes)
				)
			)
			(property "Datasheet" "https://www.murata.com/products/productdetail?partno=GRM21BR60J107ME15%23"
				(at 20.32 -15.24 0)
				(effects
					(font
						(size 1.27 1.27)
						(thickness 0.15)
					)
					(justify left bottom)
					(hide yes)
				)
			)
			(property "Description" "SMD Multilayer Ceramic Capacitor, 100 µF, 6.3 V, 0805 [2012 Metric], ± 20%, X5R, GRM Series"
				(at 0 0 0)
				(effects
					(font
						(size 1.27 1.27)
					)
					(hide yes)
				)
			)
			(property "MPN" "GRM21BR60J107ME15L"
				(at 20.32 -17.78 0)
				(effects
					(font
						(size 1.27 1.27)
						(thickness 0.15)
					)
					(justify left bottom)
					(hide yes)
				)
			)
			(property "Manufacturer" "Murata"
				(at 20.32 -20.32 0)
				(effects
					(font
						(size 1.27 1.27)
						(thickness 0.15)
					)
					(justify left bottom)
					(hide yes)
				)
			)
			(property "License" "Apache-2.0"
				(at 20.32 -22.86 0)
				(effects
					(font
						(size 1.27 1.27)
						(thickness 0.15)
					)
					(justify left bottom)
					(hide yes)
				)
			)
			(property "Author" "Antmicro"
				(at 20.32 -25.4 0)
				(effects
					(font
						(size 1.27 1.27)
						(thickness 0.15)
					)
					(justify left bottom)
					(hide yes)
				)
			)
			(property "Val" "100u"
				(at 20.32 -7.62 0)
				(effects
					(font
						(size 1.27 1.27)
						(thickness 0.15)
					)
					(justify left bottom)
				)
			)
			(property "Voltage" ""
				(at 20.32 -27.94 0)
				(effects
					(font
						(size 1.27 1.27)
					)
					(justify left bottom)
					(hide yes)
				)
			)
			(property "Dielectric" ""
				(at 20.32 -30.48 0)
				(effects
					(font
						(size 1.27 1.27)
					)
					(justify left bottom)
					(hide yes)
				)
			)
			(property "Public" "False"
				(at 20.32 -33.02 0)
				(effects
					(font
						(size 1.27 1.27)
					)
					(justify left bottom)
					(hide yes)
				)
			)
			(property "ki_keywords" "0805, SMT, CAPACITOR, PASSIVE"
				(at 0 0 0)
				(effects
					(font
						(size 1.27 1.27)
					)
					(hide yes)
				)
			)
			(symbol "C_100u_0805_0_1"
				(polyline
					(pts
						(xy 2.032 -1.524) (xy 2.032 1.524)
					)
					(stroke
						(width 0.3048)
						(type default)
					)
					(fill
						(type none)
					)
				)
				(polyline
					(pts
						(xy 3.048 -1.524) (xy 3.048 1.524)
					)
					(stroke
						(width 0.3302)
						(type default)
					)
					(fill
						(type none)
					)
				)
			)
			(symbol "C_100u_0805_1_1"
				(pin passive line
					(at 0 0 0)
					(length 2.032)
					(name "~"
						(effects
							(font
								(size 1.27 1.27)
							)
						)
					)
					(number "1"
						(effects
							(font
								(size 1.27 1.27)
							)
						)
					)
				)
				(pin passive line
					(at 5.08 0 180)
					(length 2.032)
					(name "~"
						(effects
							(font
								(size 1.27 1.27)
							)
						)
					)
					(number "2"
						(effects
							(font
								(size 1.27 1.27)
							)
						)
					)
				)
			)
		)
	(symbol "antmicroInterfaceDriversReceiversTransceivers:PI3EQX16904GL"
			(exclude_from_sim no)
			(in_bom yes)
			(on_board yes)
			(property "Reference" "U"
				(at 35.56 -2.54 0)
				(effects
					(font
						(size 1.27 1.27)
						(thickness 0.15)
					)
					(justify left bottom)
				)
			)
			(property "Value" "PI3EQX16904GL"
				(at 35.56 -10.16 0)
				(effects
					(font
						(size 1.27 1.27)
						(thickness 0.15)
					)
					(justify left bottom)
					(hide yes)
				)
			)
			(property "Footprint" "antmicro-footprints:WQFN-42-1EP_3.5x9mm_P0.5mm"
				(at 35.56 -12.7 0)
				(effects
					(font
						(size 1.27 1.27)
						(thickness 0.15)
					)
					(justify left bottom)
					(hide yes)
				)
			)
			(property "Datasheet" "https://www.diodes.com/part/view/PI3EQX16904GL"
				(at 35.56 -15.24 0)
				(effects
					(font
						(size 1.27 1.27)
						(thickness 0.15)
					)
					(justify left bottom)
					(hide yes)
				)
			)
			(property "Description" "16Gbps 4-Channel ReDriver with Linear Equalization"
				(at 0 0 0)
				(effects
					(font
						(size 1.27 1.27)
					)
					(hide yes)
				)
			)
			(property "MPN" "PI3EQX16904GLZHEX"
				(at 35.56 -5.08 0)
				(effects
					(font
						(size 1.27 1.27)
						(thickness 0.15)
					)
					(justify left bottom)
				)
			)
			(property "Manufacturer" "Diodes Incorporated"
				(at 35.56 -7.62 0)
				(effects
					(font
						(size 1.27 1.27)
						(thickness 0.15)
					)
					(justify left bottom)
					(hide yes)
				)
			)
			(property "Author" "Antmicro"
				(at 35.56 -17.78 0)
				(effects
					(font
						(size 1.27 1.27)
						(thickness 0.15)
					)
					(justify left bottom)
					(hide yes)
				)
			)
			(property "License" "Apache-2.0"
				(at 35.56 -20.32 0)
				(effects
					(font
						(size 1.27 1.27)
						(thickness 0.15)
					)
					(justify left bottom)
					(hide yes)
				)
			)
			(property "ki_keywords" "SMT, IC"
				(at 0 0 0)
				(effects
					(font
						(size 1.27 1.27)
					)
					(hide yes)
				)
			)
			(symbol "PI3EQX16904GL_1_1"
				(polyline
					(pts
						(xy 2.54 -25.4) (xy 20.32 -25.4)
					)
					(stroke
						(width 0.254)
						(type default)
					)
					(fill
						(type background)
					)
				)
				(polyline
					(pts
						(xy 2.54 -17.78) (xy 20.32 -17.78)
					)
					(stroke
						(width 0.254)
						(type default)
					)
					(fill
						(type background)
					)
				)
				(polyline
					(pts
						(xy 2.54 -10.16) (xy 20.32 -10.16)
					)
					(stroke
						(width 0.254)
						(type default)
					)
					(fill
						(type background)
					)
				)
				(polyline
					(pts
						(xy 2.54 -2.54) (xy 20.32 -2.54)
					)
					(stroke
						(width 0.254)
						(type default)
					)
					(fill
						(type background)
					)
				)
				(polyline
					(pts
						(xy 20.32 -33.02) (xy 2.54 -33.02)
					)
					(stroke
						(width 0.254)
						(type default)
					)
					(fill
						(type background)
					)
				)
				(polyline
					(pts
						(xy 10.16 -29.21) (xy 12.7 -29.21) (xy 12.065 -28.575) (xy 12.7 -29.21) (xy 12.065 -29.845)
					)
					(stroke
						(width 0.254)
						(type default)
					)
					(fill
						(type background)
					)
				)
				(polyline
					(pts
						(xy 10.16 -21.59) (xy 12.7 -21.59) (xy 12.065 -20.955) (xy 12.7 -21.59) (xy 12.065 -22.225)
					)
					(stroke
						(width 0.254)
						(type default)
					)
					(fill
						(type background)
					)
				)
				(polyline
					(pts
						(xy 10.16 -13.97) (xy 12.7 -13.97) (xy 12.065 -13.335) (xy 12.7 -13.97) (xy 12.065 -14.605)
					)
					(stroke
						(width 0.254)
						(type default)
					)
					(fill
						(type background)
					)
				)
				(polyline
					(pts
						(xy 10.16 -6.35) (xy 12.7 -6.35) (xy 12.065 -5.715) (xy 12.7 -6.35) (xy 12.065 -6.985)
					)
					(stroke
						(width 0.254)
						(type default)
					)
					(fill
						(type background)
					)
				)
				(rectangle
					(start 2.54 2.54)
					(end 20.32 -68.58)
					(stroke
						(width 0.254)
						(type default)
					)
					(fill
						(type background)
					)
				)
				(pin passive line
					(at 0 -55.88 0)
					(length 2.54)
					(name "EQ2"
						(effects
							(font
								(size 1.27 1.27)
							)
						)
					)
					(number "1"
						(effects
							(font
								(size 1.27 1.27)
							)
						)
					)
				)
				(pin input line
					(at 0 -20.32 0)
					(length 2.54)
					(name "A2RX+"
						(effects
							(font
								(size 1.27 1.27)
							)
						)
					)
					(number "10"
						(effects
							(font
								(size 1.27 1.27)
							)
						)
					)
				)
				(pin input line
					(at 0 -22.86 0)
					(length 2.54)
					(name "A2RX-"
						(effects
							(font
								(size 1.27 1.27)
							)
						)
					)
					(number "11"
						(effects
							(font
								(size 1.27 1.27)
							)
						)
					)
				)
				(pin power_in line
					(at 0 0 0)
					(length 2.54)
					(name "VCC"
						(effects
							(font
								(size 1.27 1.27)
							)
						)
					)
					(number "12"
						(effects
							(font
								(size 1.27 1.27)
							)
						)
					)
				)
				(pin input line
					(at 0 -27.94 0)
					(length 2.54)
					(name "A3RX+"
						(effects
							(font
								(size 1.27 1.27)
							)
						)
					)
					(number "13"
						(effects
							(font
								(size 1.27 1.27)
							)
						)
					)
				)
				(pin input line
					(at 0 -30.48 0)
					(length 2.54)
					(name "A3RX-"
						(effects
							(font
								(size 1.27 1.27)
							)
						)
					)
					(number "14"
						(effects
							(font
								(size 1.27 1.27)
							)
						)
					)
				)
				(pin passive line
					(at 0 0 0)
					(length 2.54) hide
					(name "VCC"
						(effects
							(font
								(size 1.27 1.27)
							)
						)
					)
					(number "15"
						(effects
							(font
								(size 1.27 1.27)
							)
						)
					)
				)
				(pin input line
					(at 0 -45.72 0)
					(length 2.54)
					(name "~{I2C_{RESET}}"
						(effects
							(font
								(size 1.27 1.27)
							)
						)
					)
					(number "16"
						(effects
							(font
								(size 1.27 1.27)
							)
						)
					)
				)
				(pin passive line
					(at 22.86 -58.42 180)
					(length 2.54)
					(name "AD1"
						(effects
							(font
								(size 1.27 1.27)
							)
						)
					)
					(number "17"
						(effects
							(font
								(size 1.27 1.27)
							)
						)
					)
				)
				(pin open_collector line
					(at 0 -35.56 0)
					(length 2.54)
					(name "SDA"
						(effects
							(font
								(size 1.27 1.27)
							)
						)
					)
					(number "18"
						(effects
							(font
								(size 1.27 1.27)
							)
						)
					)
				)
				(pin open_collector line
					(at 0 -38.1 0)
					(length 2.54)
					(name "SCL"
						(effects
							(font
								(size 1.27 1.27)
							)
						)
					)
					(number "19"
						(effects
							(font
								(size 1.27 1.27)
							)
						)
					)
				)
				(pin input line
					(at 0 -66.04 0)
					(length 2.54)
					(name "SW1"
						(effects
							(font
								(size 1.27 1.27)
							)
						)
					)
					(number "2"
						(effects
							(font
								(size 1.27 1.27)
							)
						)
					)
				)
				(pin input line
					(at 22.86 -35.56 180)
					(length 2.54)
					(name "~{PRSNT}"
						(effects
							(font
								(size 1.27 1.27)
							)
						)
					)
					(number "20"
						(effects
							(font
								(size 1.27 1.27)
							)
						)
					)
				)
				(pin input line
					(at 0 -40.64 0)
					(length 2.54)
					(name "EN_{I2C}"
						(effects
							(font
								(size 1.27 1.27)
							)
						)
					)
					(number "21"
						(effects
							(font
								(size 1.27 1.27)
							)
						)
					)
				)
				(pin input line
					(at 0 -43.18 0)
					(length 2.54)
					(name "I2C_{DONE}"
						(effects
							(font
								(size 1.27 1.27)
							)
						)
					)
					(number "22"
						(effects
							(font
								(size 1.27 1.27)
							)
						)
					)
				)
				(pin input line
					(at 22.86 -40.64 180)
					(length 2.54)
					(name "RXDET"
						(effects
							(font
								(size 1.27 1.27)
							)
						)
					)
					(number "23"
						(effects
							(font
								(size 1.27 1.27)
							)
						)
					)
				)
				(pin passive line
					(at 0 0 0)
					(length 2.54) hide
					(name "VCC"
						(effects
							(font
								(size 1.27 1.27)
							)
						)
					)
					(number "24"
						(effects
							(font
								(size 1.27 1.27)
							)
						)
					)
				)
				(pin output line
					(at 22.86 -30.48 180)
					(length 2.54)
					(name "A3TX-"
						(effects
							(font
								(size 1.27 1.27)
							)
						)
					)
					(number "25"
						(effects
							(font
								(size 1.27 1.27)
							)
						)
					)
				)
				(pin input line
					(at 22.86 -27.94 180)
					(length 2.54)
					(name "A3TX+"
						(effects
							(font
								(size 1.27 1.27)
							)
						)
					)
					(number "26"
						(effects
							(font
								(size 1.27 1.27)
							)
						)
					)
				)
				(pin passive line
					(at 0 0 0)
					(length 2.54) hide
					(name "VCC"
						(effects
							(font
								(size 1.27 1.27)
							)
						)
					)
					(number "27"
						(effects
							(font
								(size 1.27 1.27)
							)
						)
					)
				)
				(pin output line
					(at 22.86 -22.86 180)
					(length 2.54)
					(name "A2TX-"
						(effects
							(font
								(size 1.27 1.27)
							)
						)
					)
					(number "28"
						(effects
							(font
								(size 1.27 1.27)
							)
						)
					)
				)
				(pin input line
					(at 22.86 -20.32 180)
					(length 2.54)
					(name "A2TX+"
						(effects
							(font
								(size 1.27 1.27)
							)
						)
					)
					(number "29"
						(effects
							(font
								(size 1.27 1.27)
							)
						)
					)
				)
				(pin passive line
					(at 0 0 0)
					(length 2.54) hide
					(name "VCC"
						(effects
							(font
								(size 1.27 1.27)
							)
						)
					)
					(number "3"
						(effects
							(font
								(size 1.27 1.27)
							)
						)
					)
				)
				(pin passive line
					(at 0 0 0)
					(length 2.54) hide
					(name "VCC"
						(effects
							(font
								(size 1.27 1.27)
							)
						)
					)
					(number "30"
						(effects
							(font
								(size 1.27 1.27)
							)
						)
					)
				)
				(pin output line
					(at 22.86 -15.24 180)
					(length 2.54)
					(name "A1TX-"
						(effects
							(font
								(size 1.27 1.27)
							)
						)
					)
					(number "31"
						(effects
							(font
								(size 1.27 1.27)
							)
						)
					)
				)
				(pin input line
					(at 22.86 -12.7 180)
					(length 2.54)
					(name "A1TX+"
						(effects
							(font
								(size 1.27 1.27)
							)
						)
					)
					(number "32"
						(effects
							(font
								(size 1.27 1.27)
							)
						)
					)
				)
				(pin passive line
					(at 0 0 0)
					(length 2.54) hide
					(name "VCC"
						(effects
							(font
								(size 1.27 1.27)
							)
						)
					)
					(number "33"
						(effects
							(font
								(size 1.27 1.27)
							)
						)
					)
				)
				(pin output line
					(at 22.86 -7.62 180)
					(length 2.54)
					(name "A0TX-"
						(effects
							(font
								(size 1.27 1.27)
							)
						)
					)
					(number "34"
						(effects
							(font
								(size 1.27 1.27)
							)
						)
					)
				)
				(pin input line
					(at 22.86 -5.08 180)
					(length 2.54)
					(name "A0TX+"
						(effects
							(font
								(size 1.27 1.27)
							)
						)
					)
					(number "35"
						(effects
							(font
								(size 1.27 1.27)
							)
						)
					)
				)
				(pin passive line
					(at 0 0 0)
					(length 2.54) hide
					(name "VCC"
						(effects
							(font
								(size 1.27 1.27)
							)
						)
					)
					(number "36"
						(effects
							(font
								(size 1.27 1.27)
							)
						)
					)
				)
				(pin passive line
					(at 0 -60.96 0)
					(length 2.54)
					(name "FG0"
						(effects
							(font
								(size 1.27 1.27)
							)
						)
					)
					(number "37"
						(effects
							(font
								(size 1.27 1.27)
							)
						)
					)
				)
				(pin passive line
					(at 0 -63.5 0)
					(length 2.54)
					(name "FG1"
						(effects
							(font
								(size 1.27 1.27)
							)
						)
					)
					(number "38"
						(effects
							(font
								(size 1.27 1.27)
							)
						)
					)
				)
				(pin passive line
					(at 0 -50.8 0)
					(length 2.54)
					(name "EQ0"
						(effects
							(font
								(size 1.27 1.27)
							)
						)
					)
					(number "39"
						(effects
							(font
								(size 1.27 1.27)
							)
						)
					)
				)
				(pin input line
					(at 0 -5.08 0)
					(length 2.54)
					(name "A0RX+"
						(effects
							(font
								(size 1.27 1.27)
							)
						)
					)
					(number "4"
						(effects
							(font
								(size 1.27 1.27)
							)
						)
					)
				)
				(pin passive line
					(at 0 -53.34 0)
					(length 2.54)
					(name "EQ1"
						(effects
							(font
								(size 1.27 1.27)
							)
						)
					)
					(number "40"
						(effects
							(font
								(size 1.27 1.27)
							)
						)
					)
				)
				(pin passive line
					(at 22.86 -60.96 180)
					(length 2.54)
					(name "AD2"
						(effects
							(font
								(size 1.27 1.27)
							)
						)
					)
					(number "41"
						(effects
							(font
								(size 1.27 1.27)
							)
						)
					)
				)
				(pin passive line
					(at 22.86 -63.5 180)
					(length 2.54)
					(name "AD3"
						(effects
							(font
								(size 1.27 1.27)
							)
						)
					)
					(number "42"
						(effects
							(font
								(size 1.27 1.27)
							)
						)
					)
				)
				(pin power_in line
					(at 22.86 -66.04 180)
					(length 2.54)
					(name "GND"
						(effects
							(font
								(size 1.27 1.27)
							)
						)
					)
					(number "43"
						(effects
							(font
								(size 1.27 1.27)
							)
						)
					)
				)
				(pin input line
					(at 0 -7.62 0)
					(length 2.54)
					(name "A0RX-"
						(effects
							(font
								(size 1.27 1.27)
							)
						)
					)
					(number "5"
						(effects
							(font
								(size 1.27 1.27)
							)
						)
					)
				)
				(pin passive line
					(at 0 0 0)
					(length 2.54) hide
					(name "VCC"
						(effects
							(font
								(size 1.27 1.27)
							)
						)
					)
					(number "6"
						(effects
							(font
								(size 1.27 1.27)
							)
						)
					)
				)
				(pin input line
					(at 0 -12.7 0)
					(length 2.54)
					(name "A1RX+"
						(effects
							(font
								(size 1.27 1.27)
							)
						)
					)
					(number "7"
						(effects
							(font
								(size 1.27 1.27)
							)
						)
					)
				)
				(pin input line
					(at 0 -15.24 0)
					(length 2.54)
					(name "A1RX-"
						(effects
							(font
								(size 1.27 1.27)
							)
						)
					)
					(number "8"
						(effects
							(font
								(size 1.27 1.27)
							)
						)
					)
				)
				(pin passive line
					(at 0 0 0)
					(length 2.54) hide
					(name "VCC"
						(effects
							(font
								(size 1.27 1.27)
							)
						)
					)
					(number "9"
						(effects
							(font
								(size 1.27 1.27)
							)
						)
					)
				)
			)
		)
	(symbol "antmicroLogicTranslatorsLevelShifters:MAX3373EEKA+"
			(exclude_from_sim no)
			(in_bom yes)
			(on_board yes)
			(property "Reference" "U"
				(at 43.18 -2.54 0)
				(effects
					(font
						(size 1.27 1.27)
						(thickness 0.15)
					)
					(justify left bottom)
				)
			)
			(property "Value" "MAX3373EEKA+"
				(at 43.18 -7.62 0)
				(effects
					(font
						(size 1.27 1.27)
						(thickness 0.15)
					)
					(justify left bottom)
					(hide yes)
				)
			)
			(property "Footprint" "antmicro-footprints:SOT-23-8"
				(at 43.18 -10.16 0)
				(effects
					(font
						(size 1.27 1.27)
						(thickness 0.15)
					)
					(justify left bottom)
					(hide yes)
				)
			)
			(property "Datasheet" "https://www.analog.com/en/products/max3373e.html"
				(at 43.18 -12.7 0)
				(effects
					(font
						(size 1.27 1.27)
						(thickness 0.15)
					)
					(justify left bottom)
					(hide yes)
				)
			)
			(property "Description" "±15kV ESD-Protected, 1µA, 16Mbps, Dual/Quad Low-Voltage Level Translators in UCSP"
				(at 0 0 0)
				(effects
					(font
						(size 1.27 1.27)
					)
					(hide yes)
				)
			)
			(property "MPN" "MAX3373EEKA+"
				(at 43.18 -5.08 0)
				(effects
					(font
						(size 1.27 1.27)
						(thickness 0.15)
					)
					(justify left bottom)
				)
			)
			(property "Manufacturer" "Analog Devices"
				(at 43.18 -15.24 0)
				(effects
					(font
						(size 1.27 1.27)
						(thickness 0.15)
					)
					(justify left bottom)
					(hide yes)
				)
			)
			(property "Author" "Antmicro"
				(at 43.18 -17.78 0)
				(effects
					(font
						(size 1.27 1.27)
						(thickness 0.15)
					)
					(justify left bottom)
					(hide yes)
				)
			)
			(property "License" "Apache-2.0"
				(at 43.18 -20.32 0)
				(effects
					(font
						(size 1.27 1.27)
						(thickness 0.15)
					)
					(justify left bottom)
					(hide yes)
				)
			)
			(property "ki_keywords" "LEVEL-SHIFTER, IC"
				(at 0 0 0)
				(effects
					(font
						(size 1.27 1.27)
					)
					(hide yes)
				)
			)
			(symbol "MAX3373EEKA+_1_1"
				(rectangle
					(start 2.54 2.54)
					(end 25.4 -10.16)
					(stroke
						(width 0.254)
						(type default)
					)
					(fill
						(type background)
					)
				)
				(pin bidirectional line
					(at 0 -5.08 0)
					(length 2.54)
					(name "IO_V_{CC}2"
						(effects
							(font
								(size 1.27 1.27)
							)
						)
					)
					(number "1"
						(effects
							(font
								(size 1.27 1.27)
							)
						)
					)
				)
				(pin power_in line
					(at 0 -7.62 0)
					(length 2.54)
					(name "GND"
						(effects
							(font
								(size 1.27 1.27)
							)
						)
					)
					(number "2"
						(effects
							(font
								(size 1.27 1.27)
							)
						)
					)
				)
				(pin power_in line
					(at 27.94 0 180)
					(length 2.54)
					(name "V_{L}"
						(effects
							(font
								(size 1.27 1.27)
							)
						)
					)
					(number "3"
						(effects
							(font
								(size 1.27 1.27)
							)
						)
					)
				)
				(pin bidirectional line
					(at 27.94 -5.08 180)
					(length 2.54)
					(name "IO_V_{L}2"
						(effects
							(font
								(size 1.27 1.27)
							)
						)
					)
					(number "4"
						(effects
							(font
								(size 1.27 1.27)
							)
						)
					)
				)
				(pin bidirectional line
					(at 27.94 -2.54 180)
					(length 2.54)
					(name "IO_V_{L}1"
						(effects
							(font
								(size 1.27 1.27)
							)
						)
					)
					(number "5"
						(effects
							(font
								(size 1.27 1.27)
							)
						)
					)
				)
				(pin input line
					(at 27.94 -7.62 180)
					(length 2.54)
					(name "~{THREE_STATE}"
						(effects
							(font
								(size 1.27 1.27)
							)
						)
					)
					(number "6"
						(effects
							(font
								(size 1.27 1.27)
							)
						)
					)
				)
				(pin power_in line
					(at 0 0 0)
					(length 2.54)
					(name "V_{CC}"
						(effects
							(font
								(size 1.27 1.27)
							)
						)
					)
					(number "7"
						(effects
							(font
								(size 1.27 1.27)
							)
						)
					)
				)
				(pin bidirectional line
					(at 0 -2.54 0)
					(length 2.54)
					(name "IO_V_{CC}1"
						(effects
							(font
								(size 1.27 1.27)
							)
						)
					)
					(number "8"
						(effects
							(font
								(size 1.27 1.27)
							)
						)
					)
				)
			)
		)
	(symbol "antmicroMechanicalParts:MP_Pad5.4mm_Drill2.7mm"
			(pin_names hide)
			(exclude_from_sim no)
			(in_bom no)
			(on_board yes)
			(property "Reference" "MP"
				(at 20.32 -2.54 0)
				(effects
					(font
						(size 1.27 1.27)
						(thickness 0.15)
					)
					(justify left bottom)
				)
			)
			(property "Value" "MP_Pad5.4mm_Drill2.7mm"
				(at 20.32 -5.08 0)
				(effects
					(font
						(size 1.27 1.27)
						(thickness 0.15)
					)
					(justify left bottom)
				)
			)
			(property "Footprint" "antmicro-footprints:MP_Pad5.4mm_Drill2.7mm"
				(at 20.32 -7.62 0)
				(effects
					(font
						(size 1.27 1.27)
						(thickness 0.15)
					)
					(justify left bottom)
					(hide yes)
				)
			)
			(property "Datasheet" ""
				(at 16.84 -15.57 0)
				(effects
					(font
						(size 1.27 1.27)
						(thickness 0.15)
					)
					(justify left bottom)
					(hide yes)
				)
			)
			(property "Description" "Mechanical part"
				(at 0 0 0)
				(effects
					(font
						(size 1.27 1.27)
					)
					(hide yes)
				)
			)
			(property "Author" "Antmicro"
				(at 20.32 -10.16 0)
				(effects
					(font
						(size 1.27 1.27)
						(thickness 0.15)
					)
					(justify left bottom)
					(hide yes)
				)
			)
			(property "License" "Apache-2.0"
				(at 20.32 -12.7 0)
				(effects
					(font
						(size 1.27 1.27)
						(thickness 0.15)
					)
					(justify left bottom)
					(hide yes)
				)
			)
			(property "ki_keywords" "MECHANICAL"
				(at 0 0 0)
				(effects
					(font
						(size 1.27 1.27)
					)
					(hide yes)
				)
			)
			(symbol "MP_Pad5.4mm_Drill2.7mm_1_1"
				(circle
					(center 5.08 0)
					(radius 1.27)
					(stroke
						(width 0.254)
						(type default)
					)
					(fill
						(type background)
					)
				)
				(circle
					(center 5.08 0)
					(radius 2.54)
					(stroke
						(width 0.254)
						(type default)
					)
					(fill
						(type background)
					)
				)
				(pin passive line
					(at 0 0 0)
					(length 2.54)
					(name "~"
						(effects
							(font
								(size 1.27 1.27)
							)
						)
					)
					(number "1"
						(effects
							(font
								(size 1.27 1.27)
							)
						)
					)
				)
			)
		)
	(symbol "antmicroMechanicalParts:antmicro_logo"
			(exclude_from_sim no)
			(in_bom no)
			(on_board yes)
			(property "Reference" "N"
				(at 15.24 -5.08 0)
				(effects
					(font
						(size 1.27 1.27)
						(thickness 0.15)
					)
					(justify left bottom)
				)
			)
			(property "Value" "antmicro_logo"
				(at 15.24 -7.62 0)
				(effects
					(font
						(size 1.27 1.27)
						(thickness 0.15)
					)
					(justify left bottom)
				)
			)
			(property "Footprint" "antmicro-footprints:antmicro-logo"
				(at 15.24 -10.16 0)
				(effects
					(font
						(size 1.27 1.27)
						(thickness 0.15)
					)
					(justify left bottom)
					(hide yes)
				)
			)
			(property "Datasheet" ""
				(at 15.24 -12.7 0)
				(effects
					(font
						(size 1.27 1.27)
						(thickness 0.15)
					)
					(justify left bottom)
					(hide yes)
				)
			)
			(property "Description" "Mechanical part"
				(at 0 0 0)
				(effects
					(font
						(size 1.27 1.27)
					)
					(hide yes)
				)
			)
			(property "MPN" ""
				(at 0 0 0)
				(effects
					(font
						(size 1.27 1.27)
					)
				)
			)
			(property "Manufacturer" ""
				(at 15.24 -20.32 0)
				(effects
					(font
						(size 1.27 1.27)
						(thickness 0.15)
					)
					(justify left bottom)
					(hide yes)
				)
			)
			(property "Author" "Antmicro"
				(at 15.24 -15.24 0)
				(effects
					(font
						(size 1.27 1.27)
						(thickness 0.15)
					)
					(justify left bottom)
					(hide yes)
				)
			)
			(property "License" "Apache-2.0"
				(at 15.24 -17.78 0)
				(effects
					(font
						(size 1.27 1.27)
						(thickness 0.15)
					)
					(justify left bottom)
					(hide yes)
				)
			)
			(symbol "antmicro_logo_1_1"
				(text "Logo"
					(at 0 0 0)
					(effects
						(font
							(size 1.27 1.27)
							(thickness 0.15)
						)
						(justify left bottom)
					)
				)
			)
		)
	(symbol "antmicroMechanicalParts:oshw_logo"
			(exclude_from_sim no)
			(in_bom no)
			(on_board yes)
			(property "Reference" "N"
				(at 15.24 -5.08 0)
				(effects
					(font
						(size 1.27 1.27)
						(thickness 0.15)
					)
					(justify left bottom)
				)
			)
			(property "Value" "oshw_logo"
				(at 15.24 -7.62 0)
				(effects
					(font
						(size 1.27 1.27)
						(thickness 0.15)
					)
					(justify left bottom)
				)
			)
			(property "Footprint" "antmicro-footprints:oshw-logo"
				(at 15.24 -10.16 0)
				(effects
					(font
						(size 1.27 1.27)
						(thickness 0.15)
					)
					(justify left bottom)
					(hide yes)
				)
			)
			(property "Datasheet" ""
				(at 15.24 -12.7 0)
				(effects
					(font
						(size 1.27 1.27)
						(thickness 0.15)
					)
					(justify left bottom)
					(hide yes)
				)
			)
			(property "Description" "Mechanical part"
				(at 0 0 0)
				(effects
					(font
						(size 1.27 1.27)
					)
					(hide yes)
				)
			)
			(property "Author" "Antmicro"
				(at 15.24 -15.24 0)
				(effects
					(font
						(size 1.27 1.27)
						(thickness 0.15)
					)
					(justify left bottom)
					(hide yes)
				)
			)
			(property "License" "Apache-2.0"
				(at 15.24 -17.78 0)
				(effects
					(font
						(size 1.27 1.27)
						(thickness 0.15)
					)
					(justify left bottom)
					(hide yes)
				)
			)
			(property "MPN" ""
				(at 0 0 0)
				(effects
					(font
						(size 1.27 1.27)
					)
				)
			)
			(property "Manufacturer" ""
				(at 15.24 -20.32 0)
				(effects
					(font
						(size 1.27 1.27)
						(thickness 0.15)
					)
					(justify left bottom)
					(hide yes)
				)
			)
			(symbol "oshw_logo_1_1"
				(text "Logo"
					(at 0 0 0)
					(effects
						(font
							(size 1.27 1.27)
							(thickness 0.15)
						)
						(justify left bottom)
					)
				)
			)
		)
	(symbol "antmicroPMICPowerDistributionSwitchesLoadDrivers:AP22615A_TSOT26"
			(exclude_from_sim no)
			(in_bom yes)
			(on_board yes)
			(property "Reference" "U"
				(at 30.48 -2.54 0)
				(effects
					(font
						(size 1.27 1.27)
						(thickness 0.15)
					)
					(justify left bottom)
				)
			)
			(property "Value" "AP22615A_TSOT26"
				(at 30.48 -5.08 0)
				(effects
					(font
						(size 1.27 1.27)
						(thickness 0.15)
					)
					(justify left bottom)
					(hide yes)
				)
			)
			(property "Footprint" "antmicro-footprints:TSOT23-6"
				(at 30.48 -7.62 0)
				(effects
					(font
						(size 1.27 1.27)
						(thickness 0.15)
					)
					(justify left bottom)
					(hide yes)
				)
			)
			(property "Datasheet" "https://www.mouser.com/datasheet/2/115/DIOD_S_A0008958405_1-2543193.pdf"
				(at 30.48 -10.16 0)
				(effects
					(font
						(size 1.27 1.27)
						(thickness 0.15)
					)
					(justify left bottom)
					(hide yes)
				)
			)
			(property "Description" "Power Load Distribution Switch, High Side, Active High, 1 Output, 5.5 V, 3.6 A, 0.04 ohm, TSOT-26-6"
				(at 0 0 0)
				(effects
					(font
						(size 1.27 1.27)
					)
					(hide yes)
				)
			)
			(property "MPN" "AP22615AWU-7"
				(at 30.48 -12.7 0)
				(effects
					(font
						(size 1.27 1.27)
						(thickness 0.15)
					)
					(justify left bottom)
				)
			)
			(property "Manufacturer" "Diodes Incorporated"
				(at 30.48 -15.24 0)
				(effects
					(font
						(size 1.27 1.27)
						(thickness 0.15)
					)
					(justify left bottom)
					(hide yes)
				)
			)
			(property "Author" "Antmicro"
				(at 30.48 -17.78 0)
				(effects
					(font
						(size 1.27 1.27)
						(thickness 0.15)
					)
					(justify left bottom)
					(hide yes)
				)
			)
			(property "License" "Apache-2.0"
				(at 30.48 -20.32 0)
				(effects
					(font
						(size 1.27 1.27)
						(thickness 0.15)
					)
					(justify left bottom)
					(hide yes)
				)
			)
			(property "ki_keywords" "SMT, PMIC, IC, VOLTAGE"
				(at 0 0 0)
				(effects
					(font
						(size 1.27 1.27)
					)
					(hide yes)
				)
			)
			(symbol "AP22615A_TSOT26_1_1"
				(rectangle
					(start 2.54 2.54)
					(end 12.7 -7.62)
					(stroke
						(width 0.254)
						(type default)
					)
					(fill
						(type background)
					)
				)
				(pin power_out line
					(at 15.24 0 180)
					(length 2.54)
					(name "OUT"
						(effects
							(font
								(size 1.27 1.27)
							)
						)
					)
					(number "1"
						(effects
							(font
								(size 1.27 1.27)
							)
						)
					)
				)
				(pin power_in line
					(at 15.24 -5.08 180)
					(length 2.54)
					(name "GND"
						(effects
							(font
								(size 1.27 1.27)
							)
						)
					)
					(number "2"
						(effects
							(font
								(size 1.27 1.27)
							)
						)
					)
				)
				(pin output line
					(at 0 -2.54 0)
					(length 2.54)
					(name "FLG"
						(effects
							(font
								(size 1.27 1.27)
							)
						)
					)
					(number "3"
						(effects
							(font
								(size 1.27 1.27)
							)
						)
					)
				)
				(pin input line
					(at 0 -5.08 0)
					(length 2.54)
					(name "EN"
						(effects
							(font
								(size 1.27 1.27)
							)
						)
					)
					(number "4"
						(effects
							(font
								(size 1.27 1.27)
							)
						)
					)
				)
				(pin passive line
					(at 15.24 -2.54 180)
					(length 2.54)
					(name "ISET"
						(effects
							(font
								(size 1.27 1.27)
							)
						)
					)
					(number "5"
						(effects
							(font
								(size 1.27 1.27)
							)
						)
					)
				)
				(pin power_in line
					(at 0 0 0)
					(length 2.54)
					(name "IN"
						(effects
							(font
								(size 1.27 1.27)
							)
						)
					)
					(number "6"
						(effects
							(font
								(size 1.27 1.27)
							)
						)
					)
				)
			)
		)
	(symbol "antmicroPciConnectors:OCuLink_x4_Amphenol_G14A421211112HR"
			(exclude_from_sim no)
			(in_bom yes)
			(on_board yes)
			(property "Reference" "J"
				(at 39.37 -5.08 0)
				(effects
					(font
						(size 1.27 1.27)
						(thickness 0.15)
					)
					(justify left bottom)
				)
			)
			(property "Value" "OCuLink_x4_Amphenol_G14A421211112HR"
				(at 39.37 -12.7 0)
				(effects
					(font
						(size 1.27 1.27)
						(thickness 0.15)
					)
					(justify left bottom)
					(hide yes)
				)
			)
			(property "Footprint" "antmicro-footprints:Amphenol_G14A421211112HR"
				(at 39.37 -15.24 0)
				(effects
					(font
						(size 1.27 1.27)
						(thickness 0.15)
					)
					(justify left bottom)
					(hide yes)
				)
			)
			(property "Datasheet" "https://cdn.amphenol-cs.com/media/wysiwyg/files/drawing/g14a421x1bxxxhr.pdf"
				(at 39.37 -17.78 0)
				(effects
					(font
						(size 1.27 1.27)
						(thickness 0.15)
					)
					(justify left bottom)
					(hide yes)
				)
			)
			(property "Description" "I/O Connectors OCulink, Receptacle, 0.5mm pitch, 4X, R/A SMT with shell leg SMT type, 30U\" gold plating, LCP, black, T&R packing"
				(at 0 0 0)
				(effects
					(font
						(size 1.27 1.27)
					)
					(hide yes)
				)
			)
			(property "Manufacturer" "Amphenol"
				(at 39.37 -10.16 0)
				(effects
					(font
						(size 1.27 1.27)
						(thickness 0.15)
					)
					(justify left bottom)
					(hide yes)
				)
			)
			(property "MPN" "G14A421211112HR"
				(at 39.37 -7.62 0)
				(effects
					(font
						(size 1.27 1.27)
						(thickness 0.15)
					)
					(justify left bottom)
				)
			)
			(property "Author" "Antmicro"
				(at 39.37 -20.32 0)
				(effects
					(font
						(size 1.27 1.27)
						(thickness 0.15)
					)
					(justify left bottom)
					(hide yes)
				)
			)
			(property "License" "Apache-2.0"
				(at 39.37 -22.86 0)
				(effects
					(font
						(size 1.27 1.27)
						(thickness 0.15)
					)
					(justify left bottom)
					(hide yes)
				)
			)
			(property "ki_keywords" "SMT, CONNECTOR, PCIE"
				(at 0 0 0)
				(effects
					(font
						(size 1.27 1.27)
					)
					(hide yes)
				)
			)
			(symbol "OCuLink_x4_Amphenol_G14A421211112HR_1_1"
				(rectangle
					(start 3.81 2.54)
					(end 21.59 -93.98)
					(stroke
						(width 0.254)
						(type default)
					)
					(fill
						(type background)
					)
				)
				(pin power_in line
					(at 0 -2.54 0)
					(length 3.81)
					(name "V_{ACT}_RX_3V3"
						(effects
							(font
								(size 1.27 1.27)
							)
						)
					)
					(number "A1"
						(effects
							(font
								(size 1.27 1.27)
							)
						)
					)
				)
				(pin bidirectional line
					(at 0 -30.48 0)
					(length 3.81)
					(name "~{CWAKE}"
						(effects
							(font
								(size 1.27 1.27)
							)
						)
					)
					(number "A10"
						(effects
							(font
								(size 1.27 1.27)
							)
						)
					)
				)
				(pin passive line
					(at 25.4 -91.44 180)
					(length 3.81)
					(name "GND"
						(effects
							(font
								(size 1.27 1.27)
							)
						)
					)
					(number "A11"
						(effects
							(font
								(size 1.27 1.27)
							)
						)
					)
				)
				(pin bidirectional line
					(at 0 -17.78 0)
					(length 3.81)
					(name "VSP1"
						(effects
							(font
								(size 1.27 1.27)
							)
						)
					)
					(number "A12"
						(effects
							(font
								(size 1.27 1.27)
							)
						)
					)
				)
				(pin bidirectional line
					(at 0 -20.32 0)
					(length 3.81)
					(name "VSP2"
						(effects
							(font
								(size 1.27 1.27)
							)
						)
					)
					(number "A13"
						(effects
							(font
								(size 1.27 1.27)
							)
						)
					)
				)
				(pin passive line
					(at 25.4 -91.44 180)
					(length 3.81) hide
					(name "GND"
						(effects
							(font
								(size 1.27 1.27)
							)
						)
					)
					(number "A14"
						(effects
							(font
								(size 1.27 1.27)
							)
						)
					)
				)
				(pin output line
					(at 0 -50.8 0)
					(length 3.81)
					(name "PER2+"
						(effects
							(font
								(size 1.27 1.27)
							)
						)
					)
					(number "A15"
						(effects
							(font
								(size 1.27 1.27)
							)
						)
					)
				)
				(pin output line
					(at 0 -53.34 0)
					(length 3.81)
					(name "PER2-"
						(effects
							(font
								(size 1.27 1.27)
							)
						)
					)
					(number "A16"
						(effects
							(font
								(size 1.27 1.27)
							)
						)
					)
				)
				(pin passive line
					(at 25.4 -91.44 180)
					(length 3.81) hide
					(name "GND"
						(effects
							(font
								(size 1.27 1.27)
							)
						)
					)
					(number "A17"
						(effects
							(font
								(size 1.27 1.27)
							)
						)
					)
				)
				(pin output line
					(at 0 -58.42 0)
					(length 3.81)
					(name "PER3+"
						(effects
							(font
								(size 1.27 1.27)
							)
						)
					)
					(number "A18"
						(effects
							(font
								(size 1.27 1.27)
							)
						)
					)
				)
				(pin output line
					(at 0 -60.96 0)
					(length 3.81)
					(name "PER3-"
						(effects
							(font
								(size 1.27 1.27)
							)
						)
					)
					(number "A19"
						(effects
							(font
								(size 1.27 1.27)
							)
						)
					)
				)
				(pin passive line
					(at 25.4 -91.44 180)
					(length 3.81) hide
					(name "GND"
						(effects
							(font
								(size 1.27 1.27)
							)
						)
					)
					(number "A2"
						(effects
							(font
								(size 1.27 1.27)
							)
						)
					)
				)
				(pin passive line
					(at 25.4 -91.44 180)
					(length 3.81) hide
					(name "GND"
						(effects
							(font
								(size 1.27 1.27)
							)
						)
					)
					(number "A20"
						(effects
							(font
								(size 1.27 1.27)
							)
						)
					)
				)
				(pin passive line
					(at 0 0 0)
					(length 3.81)
					(name "5V"
						(effects
							(font
								(size 1.27 1.27)
							)
						)
					)
					(number "A21"
						(effects
							(font
								(size 1.27 1.27)
							)
						)
					)
				)
				(pin output line
					(at 0 -35.56 0)
					(length 3.81)
					(name "PER0+"
						(effects
							(font
								(size 1.27 1.27)
							)
						)
					)
					(number "A3"
						(effects
							(font
								(size 1.27 1.27)
							)
						)
					)
				)
				(pin output line
					(at 0 -38.1 0)
					(length 3.81)
					(name "PER0-"
						(effects
							(font
								(size 1.27 1.27)
							)
						)
					)
					(number "A4"
						(effects
							(font
								(size 1.27 1.27)
							)
						)
					)
				)
				(pin passive line
					(at 25.4 -91.44 180)
					(length 3.81) hide
					(name "GND"
						(effects
							(font
								(size 1.27 1.27)
							)
						)
					)
					(number "A5"
						(effects
							(font
								(size 1.27 1.27)
							)
						)
					)
				)
				(pin output line
					(at 0 -43.18 0)
					(length 3.81)
					(name "PER1+"
						(effects
							(font
								(size 1.27 1.27)
							)
						)
					)
					(number "A6"
						(effects
							(font
								(size 1.27 1.27)
							)
						)
					)
				)
				(pin output line
					(at 0 -45.72 0)
					(length 3.81)
					(name "PER1-"
						(effects
							(font
								(size 1.27 1.27)
							)
						)
					)
					(number "A7"
						(effects
							(font
								(size 1.27 1.27)
							)
						)
					)
				)
				(pin passive line
					(at 25.4 -91.44 180)
					(length 3.81) hide
					(name "GND"
						(effects
							(font
								(size 1.27 1.27)
							)
						)
					)
					(number "A8"
						(effects
							(font
								(size 1.27 1.27)
							)
						)
					)
				)
				(pin no_connect line
					(at 21.59 -76.2 180)
					(length 3.81) hide
					(name "NC"
						(effects
							(font
								(size 1.27 1.27)
							)
						)
					)
					(number "A9"
						(effects
							(font
								(size 1.27 1.27)
							)
						)
					)
				)
				(pin passive line
					(at 0 0 0)
					(length 3.81) hide
					(name "5V"
						(effects
							(font
								(size 1.27 1.27)
							)
						)
					)
					(number "B1"
						(effects
							(font
								(size 1.27 1.27)
							)
						)
					)
				)
				(pin bidirectional line
					(at 0 -12.7 0)
					(length 3.81)
					(name "SDA"
						(effects
							(font
								(size 1.27 1.27)
							)
						)
					)
					(number "B10"
						(effects
							(font
								(size 1.27 1.27)
							)
						)
					)
				)
				(pin passive line
					(at 25.4 -91.44 180)
					(length 3.81) hide
					(name "GND"
						(effects
							(font
								(size 1.27 1.27)
							)
						)
					)
					(number "B11"
						(effects
							(font
								(size 1.27 1.27)
							)
						)
					)
				)
				(pin bidirectional line
					(at 0 -25.4 0)
					(length 3.81)
					(name "~{PERST}"
						(effects
							(font
								(size 1.27 1.27)
							)
						)
					)
					(number "B12"
						(effects
							(font
								(size 1.27 1.27)
							)
						)
					)
				)
				(pin bidirectional line
					(at 0 -27.94 0)
					(length 3.81)
					(name "~{CPRSNT}"
						(effects
							(font
								(size 1.27 1.27)
							)
						)
					)
					(number "B13"
						(effects
							(font
								(size 1.27 1.27)
							)
						)
					)
				)
				(pin passive line
					(at 25.4 -91.44 180)
					(length 3.81) hide
					(name "GND"
						(effects
							(font
								(size 1.27 1.27)
							)
						)
					)
					(number "B14"
						(effects
							(font
								(size 1.27 1.27)
							)
						)
					)
				)
				(pin input line
					(at 0 -81.28 0)
					(length 3.81)
					(name "PET2+"
						(effects
							(font
								(size 1.27 1.27)
							)
						)
					)
					(number "B15"
						(effects
							(font
								(size 1.27 1.27)
							)
						)
					)
				)
				(pin input line
					(at 0 -83.82 0)
					(length 3.81)
					(name "PET2-"
						(effects
							(font
								(size 1.27 1.27)
							)
						)
					)
					(number "B16"
						(effects
							(font
								(size 1.27 1.27)
							)
						)
					)
				)
				(pin passive line
					(at 25.4 -91.44 180)
					(length 3.81) hide
					(name "GND"
						(effects
							(font
								(size 1.27 1.27)
							)
						)
					)
					(number "B17"
						(effects
							(font
								(size 1.27 1.27)
							)
						)
					)
				)
				(pin input line
					(at 0 -88.9 0)
					(length 3.81)
					(name "PET3+"
						(effects
							(font
								(size 1.27 1.27)
							)
						)
					)
					(number "B18"
						(effects
							(font
								(size 1.27 1.27)
							)
						)
					)
				)
				(pin input line
					(at 0 -91.44 0)
					(length 3.81)
					(name "PET3-"
						(effects
							(font
								(size 1.27 1.27)
							)
						)
					)
					(number "B19"
						(effects
							(font
								(size 1.27 1.27)
							)
						)
					)
				)
				(pin passive line
					(at 25.4 -91.44 180)
					(length 3.81) hide
					(name "GND"
						(effects
							(font
								(size 1.27 1.27)
							)
						)
					)
					(number "B2"
						(effects
							(font
								(size 1.27 1.27)
							)
						)
					)
				)
				(pin passive line
					(at 25.4 -91.44 180)
					(length 3.81) hide
					(name "GND"
						(effects
							(font
								(size 1.27 1.27)
							)
						)
					)
					(number "B20"
						(effects
							(font
								(size 1.27 1.27)
							)
						)
					)
				)
				(pin power_in line
					(at 0 -5.08 0)
					(length 3.81)
					(name "V_{ACT}_TX_3V3"
						(effects
							(font
								(size 1.27 1.27)
							)
						)
					)
					(number "B21"
						(effects
							(font
								(size 1.27 1.27)
							)
						)
					)
				)
				(pin input line
					(at 0 -66.04 0)
					(length 3.81)
					(name "PET0+"
						(effects
							(font
								(size 1.27 1.27)
							)
						)
					)
					(number "B3"
						(effects
							(font
								(size 1.27 1.27)
							)
						)
					)
				)
				(pin input line
					(at 0 -68.58 0)
					(length 3.81)
					(name "PET0-"
						(effects
							(font
								(size 1.27 1.27)
							)
						)
					)
					(number "B4"
						(effects
							(font
								(size 1.27 1.27)
							)
						)
					)
				)
				(pin passive line
					(at 25.4 -91.44 180)
					(length 3.81) hide
					(name "GND"
						(effects
							(font
								(size 1.27 1.27)
							)
						)
					)
					(number "B5"
						(effects
							(font
								(size 1.27 1.27)
							)
						)
					)
				)
				(pin input line
					(at 0 -73.66 0)
					(length 3.81)
					(name "PET1+"
						(effects
							(font
								(size 1.27 1.27)
							)
						)
					)
					(number "B6"
						(effects
							(font
								(size 1.27 1.27)
							)
						)
					)
				)
				(pin input line
					(at 0 -76.2 0)
					(length 3.81)
					(name "PET1-"
						(effects
							(font
								(size 1.27 1.27)
							)
						)
					)
					(number "B7"
						(effects
							(font
								(size 1.27 1.27)
							)
						)
					)
				)
				(pin passive line
					(at 25.4 -91.44 180)
					(length 3.81) hide
					(name "GND"
						(effects
							(font
								(size 1.27 1.27)
							)
						)
					)
					(number "B8"
						(effects
							(font
								(size 1.27 1.27)
							)
						)
					)
				)
				(pin bidirectional line
					(at 0 -10.16 0)
					(length 3.81)
					(name "SCL"
						(effects
							(font
								(size 1.27 1.27)
							)
						)
					)
					(number "B9"
						(effects
							(font
								(size 1.27 1.27)
							)
						)
					)
				)
				(pin passive line
					(at 25.4 -88.9 180)
					(length 3.81)
					(name "SH"
						(effects
							(font
								(size 1.27 1.27)
							)
						)
					)
					(number "SH"
						(effects
							(font
								(size 1.27 1.27)
							)
						)
					)
				)
			)
		)
	(symbol "antmicroResistors0402:R_0R_0402"
			(pin_numbers hide)
			(pin_names hide)
			(exclude_from_sim no)
			(in_bom yes)
			(on_board yes)
			(property "Reference" "R"
				(at 20.32 -5.08 0)
				(effects
					(font
						(size 1.27 1.27)
						(thickness 0.15)
					)
					(justify left bottom)
				)
			)
			(property "Value" "R_0R_0402"
				(at 20.32 -12.7 0)
				(effects
					(font
						(size 1.27 1.27)
						(thickness 0.15)
					)
					(justify left bottom)
					(hide yes)
				)
			)
			(property "Footprint" "antmicro-footprints:R_0402_1005Metric"
				(at 20.32 -15.24 0)
				(effects
					(font
						(size 1.27 1.27)
						(thickness 0.15)
					)
					(justify left bottom)
					(hide yes)
				)
			)
			(property "Datasheet" "https://industrial.panasonic.com/cdbs/www-data/pdf/RDA0000/AOA0000C301.pdf"
				(at 20.32 -17.78 0)
				(effects
					(font
						(size 1.27 1.27)
						(thickness 0.15)
					)
					(justify left bottom)
					(hide yes)
				)
			)
			(property "Description" "SMD Chip Resistor, Jumper, 0 ohm, 100 mW, 0402 [1005 Metric], Thick Film, General Purpose"
				(at 0 0 0)
				(effects
					(font
						(size 1.27 1.27)
					)
					(hide yes)
				)
			)
			(property "MPN" "ERJ2GE0R00X"
				(at 20.32 -20.32 0)
				(effects
					(font
						(size 1.27 1.27)
						(thickness 0.15)
					)
					(justify left bottom)
					(hide yes)
				)
			)
			(property "Manufacturer" "Panasonic"
				(at 20.32 -22.86 0)
				(effects
					(font
						(size 1.27 1.27)
						(thickness 0.15)
					)
					(justify left bottom)
					(hide yes)
				)
			)
			(property "License" "Apache-2.0"
				(at 20.32 -25.4 0)
				(effects
					(font
						(size 1.27 1.27)
						(thickness 0.15)
					)
					(justify left bottom)
					(hide yes)
				)
			)
			(property "Author" "Antmicro"
				(at 20.32 -27.94 0)
				(effects
					(font
						(size 1.27 1.27)
						(thickness 0.15)
					)
					(justify left bottom)
					(hide yes)
				)
			)
			(property "Val" "0R"
				(at 20.32 -7.62 0)
				(effects
					(font
						(size 1.27 1.27)
						(thickness 0.15)
					)
					(justify left bottom)
				)
			)
			(property "Tolerance" "~"
				(at 20.32 -10.16 0)
				(effects
					(font
						(size 1.27 1.27)
					)
					(justify left bottom)
					(hide yes)
				)
			)
			(property "Current" "1A"
				(at 20.32 -30.48 0)
				(effects
					(font
						(size 1.27 1.27)
						(thickness 0.15)
					)
					(justify left bottom)
					(hide yes)
				)
			)
			(property "ki_keywords" "0402, SMT, RESISTOR, PASSIVE"
				(at 0 0 0)
				(effects
					(font
						(size 1.27 1.27)
					)
					(hide yes)
				)
			)
			(symbol "R_0R_0402_0_1"
				(rectangle
					(start 0.635 0.889)
					(end 4.445 -0.889)
					(stroke
						(width 0.254)
						(type default)
					)
					(fill
						(type none)
					)
				)
			)
			(symbol "R_0R_0402_1_1"
				(pin passive line
					(at 0 0 0)
					(length 0.635)
					(name "~"
						(effects
							(font
								(size 1.27 1.27)
							)
						)
					)
					(number "1"
						(effects
							(font
								(size 1.27 1.27)
							)
						)
					)
				)
				(pin passive line
					(at 5.08 0 180)
					(length 0.635)
					(name "~"
						(effects
							(font
								(size 1.27 1.27)
							)
						)
					)
					(number "2"
						(effects
							(font
								(size 1.27 1.27)
							)
						)
					)
				)
			)
		)
	(symbol "antmicroResistors0402:R_10k_0402"
			(pin_numbers hide)
			(pin_names hide)
			(exclude_from_sim no)
			(in_bom yes)
			(on_board yes)
			(property "Reference" "R"
				(at 20.32 -5.08 0)
				(effects
					(font
						(size 1.27 1.27)
						(thickness 0.15)
					)
					(justify left bottom)
				)
			)
			(property "Value" "R_10k_0402"
				(at 20.32 -12.7 0)
				(effects
					(font
						(size 1.27 1.27)
						(thickness 0.15)
					)
					(justify left bottom)
					(hide yes)
				)
			)
			(property "Footprint" "antmicro-footprints:R_0402_1005Metric"
				(at 20.32 -15.24 0)
				(effects
					(font
						(size 1.27 1.27)
						(thickness 0.15)
					)
					(justify left bottom)
					(hide yes)
				)
			)
			(property "Datasheet" "https://www.bourns.com/docs/product-datasheets/cr.pdf"
				(at 20.32 -17.78 0)
				(effects
					(font
						(size 1.27 1.27)
						(thickness 0.15)
					)
					(justify left bottom)
					(hide yes)
				)
			)
			(property "Description" "SMD Chip Resistor, 10 kohm, ± 1%, 62.5 mW, 0402 [1005 Metric], Thick Film, General Purpose"
				(at 0 0 0)
				(effects
					(font
						(size 1.27 1.27)
					)
					(hide yes)
				)
			)
			(property "MPN" "CR0402-FX-1002GLF"
				(at 20.32 -20.32 0)
				(effects
					(font
						(size 1.27 1.27)
						(thickness 0.15)
					)
					(justify left bottom)
					(hide yes)
				)
			)
			(property "Manufacturer" "Bourns"
				(at 20.32 -22.86 0)
				(effects
					(font
						(size 1.27 1.27)
						(thickness 0.15)
					)
					(justify left bottom)
					(hide yes)
				)
			)
			(property "License" "Apache-2.0"
				(at 20.32 -25.4 0)
				(effects
					(font
						(size 1.27 1.27)
						(thickness 0.15)
					)
					(justify left bottom)
					(hide yes)
				)
			)
			(property "Author" "Antmicro"
				(at 20.32 -27.94 0)
				(effects
					(font
						(size 1.27 1.27)
						(thickness 0.15)
					)
					(justify left bottom)
					(hide yes)
				)
			)
			(property "Val" "10k"
				(at 20.32 -7.62 0)
				(effects
					(font
						(size 1.27 1.27)
						(thickness 0.15)
					)
					(justify left bottom)
				)
			)
			(property "Tolerance" "1%"
				(at 20.32 -10.16 0)
				(effects
					(font
						(size 1.27 1.27)
					)
					(justify left bottom)
					(hide yes)
				)
			)
			(property "ki_keywords" "0402, SMT, RESISTOR, PASSIVE"
				(at 0 0 0)
				(effects
					(font
						(size 1.27 1.27)
					)
					(hide yes)
				)
			)
			(symbol "R_10k_0402_0_1"
				(rectangle
					(start 0.635 0.889)
					(end 4.445 -0.889)
					(stroke
						(width 0.254)
						(type default)
					)
					(fill
						(type none)
					)
				)
			)
			(symbol "R_10k_0402_1_1"
				(pin passive line
					(at 0 0 0)
					(length 0.635)
					(name "~"
						(effects
							(font
								(size 1.27 1.27)
							)
						)
					)
					(number "1"
						(effects
							(font
								(size 1.27 1.27)
							)
						)
					)
				)
				(pin passive line
					(at 5.08 0 180)
					(length 0.635)
					(name "~"
						(effects
							(font
								(size 1.27 1.27)
							)
						)
					)
					(number "2"
						(effects
							(font
								(size 1.27 1.27)
							)
						)
					)
				)
			)
		)
	(symbol "antmicroResistors0402:R_11k3_0402"
			(pin_numbers hide)
			(pin_names hide)
			(exclude_from_sim no)
			(in_bom yes)
			(on_board yes)
			(property "Reference" "R"
				(at 20.32 -5.08 0)
				(effects
					(font
						(size 1.27 1.27)
						(thickness 0.15)
					)
					(justify left bottom)
				)
			)
			(property "Value" "R_11k3_0402"
				(at 20.32 -12.7 0)
				(effects
					(font
						(size 1.27 1.27)
						(thickness 0.15)
					)
					(justify left bottom)
					(hide yes)
				)
			)
			(property "Footprint" "antmicro-footprints:R_0402_1005Metric"
				(at 20.32 -15.24 0)
				(effects
					(font
						(size 1.27 1.27)
						(thickness 0.15)
					)
					(justify left bottom)
					(hide yes)
				)
			)
			(property "Datasheet" "https://www.bourns.com/docs/product-datasheets/cr.pdf"
				(at 20.32 -17.78 0)
				(effects
					(font
						(size 1.27 1.27)
						(thickness 0.15)
					)
					(justify left bottom)
					(hide yes)
				)
			)
			(property "Description" "SMD Chip Resistor, 11.3 kohm, ± 1%, 62.5 mW, 0402 [1005 Metric], Thick Film, General Purpose"
				(at 0 0 0)
				(effects
					(font
						(size 1.27 1.27)
					)
					(hide yes)
				)
			)
			(property "MPN" "CR0402-FX-1132GLF"
				(at 20.32 -20.32 0)
				(effects
					(font
						(size 1.27 1.27)
						(thickness 0.15)
					)
					(justify left bottom)
					(hide yes)
				)
			)
			(property "Manufacturer" "Bourns"
				(at 20.32 -22.86 0)
				(effects
					(font
						(size 1.27 1.27)
						(thickness 0.15)
					)
					(justify left bottom)
					(hide yes)
				)
			)
			(property "License" "Apache-2.0"
				(at 20.32 -25.4 0)
				(effects
					(font
						(size 1.27 1.27)
						(thickness 0.15)
					)
					(justify left bottom)
					(hide yes)
				)
			)
			(property "Author" "Antmicro"
				(at 20.32 -27.94 0)
				(effects
					(font
						(size 1.27 1.27)
						(thickness 0.15)
					)
					(justify left bottom)
					(hide yes)
				)
			)
			(property "Val" "11k3"
				(at 20.32 -7.62 0)
				(effects
					(font
						(size 1.27 1.27)
						(thickness 0.15)
					)
					(justify left bottom)
				)
			)
			(property "Tolerance" "1%"
				(at 20.32 -10.16 0)
				(effects
					(font
						(size 1.27 1.27)
					)
					(justify left bottom)
					(hide yes)
				)
			)
			(property "ki_keywords" "0402, SMT, RESISTOR, PASSIVE"
				(at 0 0 0)
				(effects
					(font
						(size 1.27 1.27)
					)
					(hide yes)
				)
			)
			(symbol "R_11k3_0402_0_1"
				(rectangle
					(start 0.635 0.889)
					(end 4.445 -0.889)
					(stroke
						(width 0.254)
						(type default)
					)
					(fill
						(type none)
					)
				)
			)
			(symbol "R_11k3_0402_1_1"
				(pin passive line
					(at 0 0 0)
					(length 0.635)
					(name "~"
						(effects
							(font
								(size 1.27 1.27)
							)
						)
					)
					(number "1"
						(effects
							(font
								(size 1.27 1.27)
							)
						)
					)
				)
				(pin passive line
					(at 5.08 0 180)
					(length 0.635)
					(name "~"
						(effects
							(font
								(size 1.27 1.27)
							)
						)
					)
					(number "2"
						(effects
							(font
								(size 1.27 1.27)
							)
						)
					)
				)
			)
		)
	(symbol "antmicroResistors0402:R_1k_0402"
			(pin_numbers hide)
			(pin_names hide)
			(exclude_from_sim no)
			(in_bom yes)
			(on_board yes)
			(property "Reference" "R"
				(at 20.32 -5.08 0)
				(effects
					(font
						(size 1.27 1.27)
						(thickness 0.15)
					)
					(justify left bottom)
				)
			)
			(property "Value" "R_1k_0402"
				(at 20.32 -12.7 0)
				(effects
					(font
						(size 1.27 1.27)
						(thickness 0.15)
					)
					(justify left bottom)
					(hide yes)
				)
			)
			(property "Footprint" "antmicro-footprints:R_0402_1005Metric"
				(at 20.32 -15.24 0)
				(effects
					(font
						(size 1.27 1.27)
						(thickness 0.15)
					)
					(justify left bottom)
					(hide yes)
				)
			)
			(property "Datasheet" "https://www.bourns.com/docs/product-datasheets/cr.pdf"
				(at 20.32 -17.78 0)
				(effects
					(font
						(size 1.27 1.27)
						(thickness 0.15)
					)
					(justify left bottom)
					(hide yes)
				)
			)
			(property "Description" "SMD Chip Resistor, 1 kohm, ± 1%, 63 mW, 0402 [1005 Metric], Thick Film, General Purpose"
				(at 0 0 0)
				(effects
					(font
						(size 1.27 1.27)
					)
					(hide yes)
				)
			)
			(property "MPN" "CR0402-FX-1001GLF"
				(at 20.32 -20.32 0)
				(effects
					(font
						(size 1.27 1.27)
						(thickness 0.15)
					)
					(justify left bottom)
					(hide yes)
				)
			)
			(property "Manufacturer" "Bourns"
				(at 20.32 -22.86 0)
				(effects
					(font
						(size 1.27 1.27)
						(thickness 0.15)
					)
					(justify left bottom)
					(hide yes)
				)
			)
			(property "License" "Apache-2.0"
				(at 20.32 -25.4 0)
				(effects
					(font
						(size 1.27 1.27)
						(thickness 0.15)
					)
					(justify left bottom)
					(hide yes)
				)
			)
			(property "Author" "Antmicro"
				(at 20.32 -27.94 0)
				(effects
					(font
						(size 1.27 1.27)
						(thickness 0.15)
					)
					(justify left bottom)
					(hide yes)
				)
			)
			(property "Val" "1k"
				(at 20.32 -7.62 0)
				(effects
					(font
						(size 1.27 1.27)
						(thickness 0.15)
					)
					(justify left bottom)
				)
			)
			(property "Tolerance" "1%"
				(at 20.32 -10.16 0)
				(effects
					(font
						(size 1.27 1.27)
					)
					(justify left bottom)
					(hide yes)
				)
			)
			(property "ki_keywords" "0402, SMT, RESISTOR, PASSIVE"
				(at 0 0 0)
				(effects
					(font
						(size 1.27 1.27)
					)
					(hide yes)
				)
			)
			(symbol "R_1k_0402_0_1"
				(rectangle
					(start 0.635 0.889)
					(end 4.445 -0.889)
					(stroke
						(width 0.254)
						(type default)
					)
					(fill
						(type none)
					)
				)
			)
			(symbol "R_1k_0402_1_1"
				(pin passive line
					(at 0 0 0)
					(length 0.635)
					(name "~"
						(effects
							(font
								(size 1.27 1.27)
							)
						)
					)
					(number "1"
						(effects
							(font
								(size 1.27 1.27)
							)
						)
					)
				)
				(pin passive line
					(at 5.08 0 180)
					(length 0.635)
					(name "~"
						(effects
							(font
								(size 1.27 1.27)
							)
						)
					)
					(number "2"
						(effects
							(font
								(size 1.27 1.27)
							)
						)
					)
				)
			)
		)
	(symbol "antmicroResistors0402:R_5k6_0402"
			(pin_numbers hide)
			(pin_names hide)
			(exclude_from_sim no)
			(in_bom yes)
			(on_board yes)
			(property "Reference" "R"
				(at 20.32 -5.08 0)
				(effects
					(font
						(size 1.27 1.27)
						(thickness 0.15)
					)
					(justify left bottom)
				)
			)
			(property "Value" "R_5k6_0402"
				(at 20.32 -12.7 0)
				(effects
					(font
						(size 1.27 1.27)
						(thickness 0.15)
					)
					(justify left bottom)
					(hide yes)
				)
			)
			(property "Footprint" "antmicro-footprints:R_0402_1005Metric"
				(at 20.32 -15.24 0)
				(effects
					(font
						(size 1.27 1.27)
						(thickness 0.15)
					)
					(justify left bottom)
					(hide yes)
				)
			)
			(property "Datasheet" "https://www.bourns.com/docs/product-datasheets/cr.pdf"
				(at 20.32 -17.78 0)
				(effects
					(font
						(size 1.27 1.27)
						(thickness 0.15)
					)
					(justify left bottom)
					(hide yes)
				)
			)
			(property "Description" "SMD Chip Resistor, 5.6 kohm, ± 1%, 62.5 mW, 0402 [1005 Metric], Thick Film, General Purpose"
				(at 0 0 0)
				(effects
					(font
						(size 1.27 1.27)
					)
					(hide yes)
				)
			)
			(property "MPN" "CR0402-FX-5601GLF"
				(at 20.32 -20.32 0)
				(effects
					(font
						(size 1.27 1.27)
						(thickness 0.15)
					)
					(justify left bottom)
					(hide yes)
				)
			)
			(property "Manufacturer" "Bourns"
				(at 20.32 -22.86 0)
				(effects
					(font
						(size 1.27 1.27)
						(thickness 0.15)
					)
					(justify left bottom)
					(hide yes)
				)
			)
			(property "License" "Apache-2.0"
				(at 20.32 -25.4 0)
				(effects
					(font
						(size 1.27 1.27)
						(thickness 0.15)
					)
					(justify left bottom)
					(hide yes)
				)
			)
			(property "Author" "Antmicro"
				(at 20.32 -27.94 0)
				(effects
					(font
						(size 1.27 1.27)
						(thickness 0.15)
					)
					(justify left bottom)
					(hide yes)
				)
			)
			(property "Val" "5k6"
				(at 20.32 -7.62 0)
				(effects
					(font
						(size 1.27 1.27)
						(thickness 0.15)
					)
					(justify left bottom)
				)
			)
			(property "Tolerance" "1%"
				(at 20.32 -10.16 0)
				(effects
					(font
						(size 1.27 1.27)
					)
					(justify left bottom)
					(hide yes)
				)
			)
			(property "ki_keywords" "0402, SMT, RESISTOR, PASSIVE"
				(at 0 0 0)
				(effects
					(font
						(size 1.27 1.27)
					)
					(hide yes)
				)
			)
			(symbol "R_5k6_0402_0_1"
				(rectangle
					(start 0.635 0.889)
					(end 4.445 -0.889)
					(stroke
						(width 0.254)
						(type default)
					)
					(fill
						(type none)
					)
				)
			)
			(symbol "R_5k6_0402_1_1"
				(pin passive line
					(at 0 0 0)
					(length 0.635)
					(name "~"
						(effects
							(font
								(size 1.27 1.27)
							)
						)
					)
					(number "1"
						(effects
							(font
								(size 1.27 1.27)
							)
						)
					)
				)
				(pin passive line
					(at 5.08 0 180)
					(length 0.635)
					(name "~"
						(effects
							(font
								(size 1.27 1.27)
							)
						)
					)
					(number "2"
						(effects
							(font
								(size 1.27 1.27)
							)
						)
					)
				)
			)
		)
	(symbol "antmicroTestPoints:TP_0.75mm_SMD"
			(pin_names hide)
			(exclude_from_sim no)
			(in_bom no)
			(on_board yes)
			(property "Reference" "TP"
				(at 10.16 -1.27 0)
				(effects
					(font
						(size 1.27 1.27)
						(thickness 0.15)
					)
					(justify left bottom)
				)
			)
			(property "Value" "TP_0.75mm_SMD"
				(at 10.16 -3.81 0)
				(effects
					(font
						(size 1.27 1.27)
						(thickness 0.15)
					)
					(justify left bottom)
					(hide yes)
				)
			)
			(property "Footprint" "antmicro-footprints:TP_SMD_0.75mm"
				(at 10.16 -6.35 0)
				(effects
					(font
						(size 1.27 1.27)
						(thickness 0.15)
					)
					(justify left bottom)
					(hide yes)
				)
			)
			(property "Datasheet" ""
				(at 17.78 -12.7 0)
				(effects
					(font
						(size 1.27 1.27)
						(thickness 0.15)
					)
					(justify left bottom)
					(hide yes)
				)
			)
			(property "Description" "SMT test point"
				(at 0 0 0)
				(effects
					(font
						(size 1.27 1.27)
					)
					(hide yes)
				)
			)
			(property "MPN" ""
				(at 10.795 -11.43 0)
				(effects
					(font
						(size 1.27 1.27)
						(thickness 0.15)
					)
					(justify left bottom)
					(hide yes)
				)
			)
			(property "Manufacturer" ""
				(at 10.795 -6.35 0)
				(effects
					(font
						(size 1.27 1.27)
						(thickness 0.15)
					)
					(justify left bottom)
					(hide yes)
				)
			)
			(property "Author" "Antmicro"
				(at 10.16 -8.89 0)
				(effects
					(font
						(size 1.27 1.27)
						(thickness 0.15)
					)
					(justify left bottom)
					(hide yes)
				)
			)
			(property "License" "Apache-2.0"
				(at 10.16 -11.43 0)
				(effects
					(font
						(size 1.27 1.27)
						(thickness 0.15)
					)
					(justify left bottom)
					(hide yes)
				)
			)
			(property "ki_keywords" "TESTPOINT"
				(at 0 0 0)
				(effects
					(font
						(size 1.27 1.27)
					)
					(hide yes)
				)
			)
			(symbol "TP_0.75mm_SMD_1_1"
				(circle
					(center 3.175 0)
					(radius 0.635)
					(stroke
						(width 0.254)
						(type default)
					)
					(fill
						(type none)
					)
				)
				(pin passive line
					(at 0 0 0)
					(length 2.54)
					(name "1"
						(effects
							(font
								(size 1.27 1.27)
							)
						)
					)
					(number "1"
						(effects
							(font
								(size 1.27 1.27)
							)
						)
					)
				)
			)
		)
	(symbol "antmicroTestPoints:TP_1.5mm_SMD"
			(pin_names hide)
			(exclude_from_sim no)
			(in_bom no)
			(on_board yes)
			(property "Reference" "TP"
				(at 15.24 -5.08 0)
				(effects
					(font
						(size 1.27 1.27)
						(thickness 0.15)
					)
					(justify left bottom)
				)
			)
			(property "Value" "TP_1.5mm_SMD"
				(at 15.24 -7.62 0)
				(effects
					(font
						(size 1.27 1.27)
						(thickness 0.15)
					)
					(justify left bottom)
					(hide yes)
				)
			)
			(property "Footprint" "antmicro-footprints:TP_SMD_1.5mm"
				(at 15.24 -10.16 0)
				(effects
					(font
						(size 1.27 1.27)
						(thickness 0.15)
					)
					(justify left bottom)
					(hide yes)
				)
			)
			(property "Datasheet" ""
				(at 17.78 -12.7 0)
				(effects
					(font
						(size 1.27 1.27)
						(thickness 0.15)
					)
					(justify left bottom)
					(hide yes)
				)
			)
			(property "Description" "test point, SMT"
				(at 0 0 0)
				(effects
					(font
						(size 1.27 1.27)
					)
					(hide yes)
				)
			)
			(property "MPN" ""
				(at 0 0 0)
				(effects
					(font
						(size 1.27 1.27)
					)
					(hide yes)
				)
			)
			(property "Manufacturer" ""
				(at 0 0 0)
				(effects
					(font
						(size 1.27 1.27)
					)
					(hide yes)
				)
			)
			(property "Author" "Antmicro"
				(at 15.24 -15.24 0)
				(effects
					(font
						(size 1.27 1.27)
						(thickness 0.15)
					)
					(justify left bottom)
					(hide yes)
				)
			)
			(property "License" "Apache-2.0"
				(at 15.24 -17.78 0)
				(effects
					(font
						(size 1.27 1.27)
						(thickness 0.15)
					)
					(justify left bottom)
					(hide yes)
				)
			)
			(property "ki_keywords" "TESTPOINT"
				(at 0 0 0)
				(effects
					(font
						(size 1.27 1.27)
					)
					(hide yes)
				)
			)
			(symbol "TP_1.5mm_SMD_1_1"
				(circle
					(center 3.175 0)
					(radius 0.635)
					(stroke
						(width 0.254)
						(type default)
					)
					(fill
						(type none)
					)
				)
				(pin passive line
					(at 0 0 0)
					(length 2.54)
					(name "1"
						(effects
							(font
								(size 1.27 1.27)
							)
						)
					)
					(number "1"
						(effects
							(font
								(size 1.27 1.27)
							)
						)
					)
				)
			)
		)
	(symbol "antmicropower:+1V8"
			(power)
			(pin_numbers hide)
			(pin_names hide)
			(exclude_from_sim no)
			(in_bom yes)
			(on_board yes)
			(property "Reference" "#PWR"
				(at 15.24 -2.54 0)
				(effects
					(font
						(size 1.27 1.27)
						(thickness 0.15)
					)
					(justify left bottom)
					(hide yes)
				)
			)
			(property "Value" "+1V8"
				(at -3.175 2.54 0)
				(effects
					(font
						(size 1.27 1.27)
						(thickness 0.15)
					)
					(justify left bottom)
				)
			)
			(property "Footprint" ""
				(at 15.24 -7.62 0)
				(effects
					(font
						(size 1.27 1.27)
						(thickness 0.15)
					)
					(justify left bottom)
					(hide yes)
				)
			)
			(property "Datasheet" ""
				(at 15.24 -10.16 0)
				(effects
					(font
						(size 1.27 1.27)
						(thickness 0.15)
					)
					(justify left bottom)
					(hide yes)
				)
			)
			(property "Description" ""
				(at 0 0 0)
				(effects
					(font
						(size 1.27 1.27)
					)
					(hide yes)
				)
			)
			(property "Author" "Antmicro"
				(at 15.24 -5.08 0)
				(effects
					(font
						(size 1.27 1.27)
						(thickness 0.15)
					)
					(justify left bottom)
					(hide yes)
				)
			)
			(property "License" "Apache-2.0"
				(at 15.24 -7.62 0)
				(effects
					(font
						(size 1.27 1.27)
						(thickness 0.15)
					)
					(justify left bottom)
					(hide yes)
				)
			)
			(symbol "+1V8_1_1"
				(polyline
					(pts
						(xy -0.762 1.27) (xy 0 2.54)
					)
					(stroke
						(width 0)
						(type default)
					)
					(fill
						(type background)
					)
				)
				(polyline
					(pts
						(xy 0 0) (xy 0 2.54)
					)
					(stroke
						(width 0)
						(type default)
					)
					(fill
						(type background)
					)
				)
				(polyline
					(pts
						(xy 0 2.54) (xy 0.762 1.27)
					)
					(stroke
						(width 0)
						(type default)
					)
					(fill
						(type background)
					)
				)
				(pin power_in line
					(at 0 0 90)
					(length 0) hide
					(name "+1V8"
						(effects
							(font
								(size 1.27 1.27)
							)
						)
					)
					(number "1"
						(effects
							(font
								(size 1.27 1.27)
							)
						)
					)
				)
			)
		)
	(symbol "antmicropower:+3.3V"
			(power)
			(pin_names
				(offset 0)
			)
			(exclude_from_sim no)
			(in_bom yes)
			(on_board yes)
			(property "Reference" "#PWR"
				(at 0 -3.81 0)
				(effects
					(font
						(size 1.27 1.27)
					)
					(hide yes)
				)
			)
			(property "Value" "+3.3V"
				(at 0 3.556 0)
				(effects
					(font
						(size 1.27 1.27)
					)
				)
			)
			(property "Footprint" ""
				(at 0 0 0)
				(effects
					(font
						(size 1.27 1.27)
					)
					(hide yes)
				)
			)
			(property "Datasheet" ""
				(at 0 0 0)
				(effects
					(font
						(size 1.27 1.27)
					)
					(hide yes)
				)
			)
			(property "Description" ""
				(at 0 0 0)
				(effects
					(font
						(size 1.27 1.27)
					)
					(hide yes)
				)
			)
			(symbol "+3.3V_0_1"
				(polyline
					(pts
						(xy -0.762 1.27) (xy 0 2.54)
					)
					(stroke
						(width 0)
						(type default)
					)
					(fill
						(type none)
					)
				)
				(polyline
					(pts
						(xy 0 0) (xy 0 2.54)
					)
					(stroke
						(width 0)
						(type default)
					)
					(fill
						(type none)
					)
				)
				(polyline
					(pts
						(xy 0 2.54) (xy 0.762 1.27)
					)
					(stroke
						(width 0)
						(type default)
					)
					(fill
						(type none)
					)
				)
			)
			(symbol "+3.3V_1_1"
				(pin power_in line
					(at 0 0 90)
					(length 0) hide
					(name "+3V3"
						(effects
							(font
								(size 1.27 1.27)
							)
						)
					)
					(number "1"
						(effects
							(font
								(size 1.27 1.27)
							)
						)
					)
				)
			)
		)
	(symbol "antmicropower:+3V3"
			(power)
			(pin_numbers hide)
			(pin_names hide)
			(exclude_from_sim no)
			(in_bom yes)
			(on_board yes)
			(property "Reference" "#PWR"
				(at 15.24 0 0)
				(effects
					(font
						(size 1.27 1.27)
						(thickness 0.15)
					)
					(justify left bottom)
					(hide yes)
				)
			)
			(property "Value" "+3V3"
				(at -3.175 2.54 0)
				(effects
					(font
						(size 1.27 1.27)
						(thickness 0.15)
					)
					(justify left bottom)
				)
			)
			(property "Footprint" ""
				(at 15.24 -7.62 0)
				(effects
					(font
						(size 1.27 1.27)
						(thickness 0.15)
					)
					(justify left bottom)
					(hide yes)
				)
			)
			(property "Datasheet" ""
				(at 15.24 -10.16 0)
				(effects
					(font
						(size 1.27 1.27)
						(thickness 0.15)
					)
					(justify left bottom)
					(hide yes)
				)
			)
			(property "Description" ""
				(at 0 0 0)
				(effects
					(font
						(size 1.27 1.27)
					)
					(hide yes)
				)
			)
			(property "Author" "Antmicro"
				(at 15.24 -2.54 0)
				(effects
					(font
						(size 1.27 1.27)
						(thickness 0.15)
					)
					(justify left bottom)
					(hide yes)
				)
			)
			(property "License" "Apache-2.0"
				(at 15.24 -5.08 0)
				(effects
					(font
						(size 1.27 1.27)
						(thickness 0.15)
					)
					(justify left bottom)
					(hide yes)
				)
			)
			(symbol "+3V3_0_1"
				(polyline
					(pts
						(xy 0 0) (xy 0 2.54)
					)
					(stroke
						(width 0)
						(type default)
					)
					(fill
						(type none)
					)
				)
				(polyline
					(pts
						(xy 0 2.54) (xy -0.762 1.27)
					)
					(stroke
						(width 0)
						(type default)
					)
					(fill
						(type none)
					)
				)
				(polyline
					(pts
						(xy 0 2.54) (xy 0.762 1.27)
					)
					(stroke
						(width 0)
						(type default)
					)
					(fill
						(type none)
					)
				)
			)
			(symbol "+3V3_1_1"
				(pin power_in line
					(at 0 0 90)
					(length 0) hide
					(name "+3V3"
						(effects
							(font
								(size 1.27 1.27)
							)
						)
					)
					(number "1"
						(effects
							(font
								(size 1.27 1.27)
							)
						)
					)
				)
			)
		)
	(symbol "antmicropower:+5V"
			(power)
			(pin_numbers hide)
			(pin_names hide)
			(exclude_from_sim no)
			(in_bom yes)
			(on_board yes)
			(property "Reference" "#PWR"
				(at 15.24 -2.54 0)
				(effects
					(font
						(size 1.27 1.27)
						(thickness 0.15)
					)
					(justify left bottom)
					(hide yes)
				)
			)
			(property "Value" "+5V"
				(at 15.24 -5.08 0)
				(effects
					(font
						(size 1.27 1.27)
						(thickness 0.15)
					)
					(justify left bottom)
				)
			)
			(property "Footprint" ""
				(at 15.24 -7.62 0)
				(effects
					(font
						(size 1.27 1.27)
						(thickness 0.15)
					)
					(justify left bottom)
					(hide yes)
				)
			)
			(property "Datasheet" ""
				(at 15.24 -10.16 0)
				(effects
					(font
						(size 1.27 1.27)
						(thickness 0.15)
					)
					(justify left bottom)
					(hide yes)
				)
			)
			(property "Description" ""
				(at 0 0 0)
				(effects
					(font
						(size 1.27 1.27)
					)
					(hide yes)
				)
			)
			(property "Author" "Antmicro"
				(at 15.24 -7.62 0)
				(effects
					(font
						(size 1.27 1.27)
						(thickness 0.15)
					)
					(justify left bottom)
					(hide yes)
				)
			)
			(property "License" "Apache-2.0"
				(at 15.24 -10.16 0)
				(effects
					(font
						(size 1.27 1.27)
						(thickness 0.15)
					)
					(justify left bottom)
					(hide yes)
				)
			)
			(symbol "+5V_1_1"
				(polyline
					(pts
						(xy -0.762 1.27) (xy 0 2.54)
					)
					(stroke
						(width 0)
						(type default)
					)
					(fill
						(type background)
					)
				)
				(polyline
					(pts
						(xy 0 0) (xy 0 2.54)
					)
					(stroke
						(width 0)
						(type default)
					)
					(fill
						(type background)
					)
				)
				(polyline
					(pts
						(xy 0 2.54) (xy 0.762 1.27)
					)
					(stroke
						(width 0)
						(type default)
					)
					(fill
						(type background)
					)
				)
				(pin power_in line
					(at 0 0 90)
					(length 0)
					(name "+5V"
						(effects
							(font
								(size 1.27 1.27)
							)
						)
					)
					(number "1"
						(effects
							(font
								(size 1.27 1.27)
							)
						)
					)
				)
			)
		)
	(symbol "antmicropower:GND"
			(power)
			(pin_numbers hide)
			(pin_names hide)
			(exclude_from_sim no)
			(in_bom yes)
			(on_board yes)
			(property "Reference" "#PWR"
				(at 8.89 -2.54 0)
				(effects
					(font
						(size 1.27 1.27)
						(thickness 0.15)
					)
					(justify left bottom)
					(hide yes)
				)
			)
			(property "Value" "GND"
				(at 8.89 -5.08 0)
				(effects
					(font
						(size 1.27 1.27)
						(thickness 0.15)
					)
					(justify left bottom)
				)
			)
			(property "Footprint" ""
				(at 8.89 -7.62 0)
				(effects
					(font
						(size 1.27 1.27)
						(thickness 0.15)
					)
					(justify left bottom)
					(hide yes)
				)
			)
			(property "Datasheet" ""
				(at 8.89 -12.7 0)
				(effects
					(font
						(size 1.27 1.27)
						(thickness 0.15)
					)
					(justify left bottom)
					(hide yes)
				)
			)
			(property "Description" ""
				(at 0 0 0)
				(effects
					(font
						(size 1.27 1.27)
					)
					(hide yes)
				)
			)
			(property "Author" "Antmicro"
				(at 8.89 -7.62 0)
				(effects
					(font
						(size 1.27 1.27)
						(thickness 0.15)
					)
					(justify left bottom)
					(hide yes)
				)
			)
			(property "License" "Apache-2.0"
				(at 8.89 -10.16 0)
				(effects
					(font
						(size 1.27 1.27)
						(thickness 0.15)
					)
					(justify left bottom)
					(hide yes)
				)
			)
			(symbol "GND_1_1"
				(polyline
					(pts
						(xy 0 0) (xy 0 -1.27) (xy 1.27 -1.27) (xy 0 -2.54) (xy -1.27 -1.27) (xy 0 -1.27)
					)
					(stroke
						(width 0)
						(type default)
					)
					(fill
						(type none)
					)
				)
				(pin power_in line
					(at 0 0 270)
					(length 0)
					(name "GND"
						(effects
							(font
								(size 1.27 1.27)
							)
						)
					)
					(number "1"
						(effects
							(font
								(size 1.27 1.27)
							)
						)
					)
				)
			)
		)
	(symbol "antmicropower:PWR_FLAG"
			(power)
			(pin_numbers hide)
			(pin_names
				(offset 0) hide)
			(exclude_from_sim no)
			(in_bom yes)
			(on_board yes)
			(property "Reference" "#FLG"
				(at 0 1.905 0)
				(effects
					(font
						(size 1.27 1.27)
					)
					(hide yes)
				)
			)
			(property "Value" "PWR_FLAG"
				(at 0 3.81 0)
				(effects
					(font
						(size 1.27 1.27)
					)
				)
			)
			(property "Footprint" ""
				(at 0 0 0)
				(effects
					(font
						(size 1.27 1.27)
					)
					(hide yes)
				)
			)
			(property "Datasheet" ""
				(at 0 0 0)
				(effects
					(font
						(size 1.27 1.27)
					)
					(hide yes)
				)
			)
			(property "Description" ""
				(at 0 0 0)
				(effects
					(font
						(size 1.27 1.27)
					)
					(hide yes)
				)
			)
			(symbol "PWR_FLAG_0_0"
				(pin power_out line
					(at 0 0 90)
					(length 0)
					(name "pwr"
						(effects
							(font
								(size 1.27 1.27)
							)
						)
					)
					(number "1"
						(effects
							(font
								(size 1.27 1.27)
							)
						)
					)
				)
			)
			(symbol "PWR_FLAG_0_1"
				(polyline
					(pts
						(xy 0 0) (xy 0 1.27) (xy -1.016 1.905) (xy 0 2.54) (xy 1.016 1.905) (xy 0 1.27)
					)
					(stroke
						(width 0)
						(type default)
					)
					(fill
						(type none)
					)
				)
			)
		)
)
